FILE_TYPE = MACRO_DRAWING;
SET COLOR_WIRE YELLOW;
SET COLOR_PROP ORANGE;
SET COLOR_DOT WHITE;
SET COLOR_ARC YELLOW;
SET COLOR_BODY GREEN;
SET COLOR_NOTE PURPLE;
SET PROP_DISPLAY VALUE;
SET PAGE_NUMBER P246;
FORCEADD UNIVERSAL_GND..1
(-4075 3125);
FORCEPROP 3 LASTPIN (-4075 3175) SIG_NAME GND\g
J 0
(-4065 3185);
DISPLAY 0.659574 (-4065 3185);
PAINT MONO (-4065 3185);
DISPLAY INVISIBLE (-4065 3185);
FORCEPROP 1 LAST PATH I1
J 0
(-4000 3125);
DISPLAY 0.872340 (-4000 3125);
PAINT AQUA (-4000 3125);
DISPLAY INVISIBLE (-4000 3125);
FORCEPROP 2 LAST BOM_COST VR_SYSTEM 
J 0
(-4375 3200);
DISPLAY 0.680851 (-4375 3200);
DISPLAY INVISIBLE (-4375 3200);
FORCEPROP 1 LAST HDL_POWER GND
J 1
(-4050 3050);
DISPLAY 0.872340 (-4050 3050);
PAINT GREEN (-4050 3050);
DISPLAY INVISIBLE (-4050 3050);
FORCEPROP 2 LAST CDS_LIB logical_power
J 0
(-4075 3125);
DISPLAY INVISIBLE (-4075 3125);
FORCEPROP 0 LAST VOLTAGE 0
J 0
(-4075 3125);
PAINT SKYBLUE (-4075 3125);
DISPLAY INVISIBLE (-4075 3125);
FORCEADD Q_RES..1
(-6275 4925);
FORCEPROP 1 LAST PART_NUMBER CS00002JB13
J 0
(-6425 5000);
DISPLAY 0.617021 (-6425 5000);
DISPLAY INVISIBLE (-6425 5000);
FORCEPROP 1 LAST MATERIAL EMPTY
J 0
(-6025 4925);
DISPLAY 0.617021 (-6025 4925);
PAINT RED (-6025 4925);
FORCEPROP 1 LAST VALUE 0
J 2
(-6125 4925);
DISPLAY 0.617021 (-6125 4925);
FORCEPROP 1 LAST WATTAGE 1/16W
J 2
(-6075 5050);
DISPLAY 0.617021 (-6075 5050);
FORCEPROP 1 LAST PACK_TYPE 0402LF
J 0
(-6425 5050);
DISPLAY 0.617021 (-6425 5050);
FORCEPROP 1 LAST TOLERANCE 5%
J 0
(-6100 4925);
DISPLAY 0.617021 (-6100 4925);
FORCEPROP 1 LAST $LOCATION R1607
J 0
(-6525 4925);
DISPLAY 0.638298 (-6525 4925);
FORCEPROP 1 LASTPIN (-6375 4925) $PN 1
J 0
(-6363 4937);
DISPLAY 0.787234 (-6363 4937);
FORCEPROP 1 LASTPIN (-6175 4925) $PN 2
J 0
(-6213 4937);
DISPLAY 0.787234 (-6213 4937);
FORCEPROP 1 LAST PATH I10
J 0
(-6325 5075);
DISPLAY 0.978723 (-6325 5075);
PAINT WHITE (-6325 5075);
DISPLAY INVISIBLE (-6325 5075);
FORCEPROP 2 LAST BOM_COST VR_SYSTEM 
J 0
(-6325 5075);
DISPLAY 0.680851 (-6325 5075);
DISPLAY INVISIBLE (-6325 5075);
FORCEPROP 2 LAST CDS_LIB pure_quanta
J 0
(-6275 4925);
PAINT MONO (-6275 4925);
DISPLAY INVISIBLE (-6275 4925);
FORCEPROP 2 LAST CDS_LOCATION R1607
J 0
(-6325 5125);
DISPLAY 1.021277 (-6325 5125);
DISPLAY INVISIBLE (-6325 5125);
FORCEPROP 2 LAST $SEC 1
J 0
(-6325 5125);
DISPLAY 0.680851 (-6325 5125);
PAINT MONO (-6325 5125);
DISPLAY INVISIBLE (-6325 5125);
FORCEPROP 2 LAST CDS_SEC 1
J 0
(-6325 5125);
DISPLAY 1.021277 (-6325 5125);
DISPLAY INVISIBLE (-6325 5125);
FORCEADD UNIVERSAL_GND..1
(-2025 3300);
FORCEPROP 3 LASTPIN (-2025 3350) SIG_NAME GND\g
J 0
(-2015 3360);
DISPLAY 0.659574 (-2015 3360);
PAINT MONO (-2015 3360);
DISPLAY INVISIBLE (-2015 3360);
FORCEPROP 2 LAST BOM_COST VR_SYSTEM 
J 0
(-2325 3375);
DISPLAY 0.680851 (-2325 3375);
DISPLAY INVISIBLE (-2325 3375);
FORCEPROP 1 LAST HDL_POWER GND
J 1
(-2000 3225);
DISPLAY 0.872340 (-2000 3225);
PAINT GREEN (-2000 3225);
DISPLAY INVISIBLE (-2000 3225);
FORCEPROP 0 LAST VOLTAGE 0
J 0
(-2025 3300);
PAINT SKYBLUE (-2025 3300);
DISPLAY INVISIBLE (-2025 3300);
FORCEPROP 1 LAST PATH I100
J 0
(-1950 3300);
DISPLAY 0.872340 (-1950 3300);
PAINT AQUA (-1950 3300);
DISPLAY INVISIBLE (-1950 3300);
FORCEPROP 2 LAST CDS_LIB logical_power
J 0
(-2025 3300);
DISPLAY INVISIBLE (-2025 3300);
FORCEADD UNIVERSAL_POWER..1
(-2025 4550);
FORCEPROP 3 LASTPIN (-2025 4500) SIG_NAME P12V_AUX\g
J 0
(-2015 4510);
DISPLAY 0.659574 (-2015 4510);
PAINT MONO (-2015 4510);
DISPLAY INVISIBLE (-2015 4510);
FORCEPROP 1 LAST HDL_POWER P12V_AUX
J 1
(-2025 4600);
DISPLAY 0.617021 (-2025 4600);
PAINT GREEN (-2025 4600);
FORCEPROP 2 LAST CDS_LIB logical_power
J 0
(-2025 4550);
DISPLAY INVISIBLE (-2025 4550);
FORCEPROP 1 LAST PATH I101
J 0
(-1975 4575);
DISPLAY 0.872340 (-1975 4575);
PAINT AQUA (-1975 4575);
DISPLAY INVISIBLE (-1975 4575);
FORCEPROP 2 LAST BOM_COST VR_SYSTEM 
J 0
(-2025 4650);
DISPLAY 0.680851 (-2025 4650);
DISPLAY INVISIBLE (-2025 4650);
FORCEADD Q_RES..2
(-2025 4275);
FORCEPROP 1 LAST PART_NUMBER CS41002FB09
J 0
(-1985 4150);
DISPLAY 0.617021 (-1985 4150);
DISPLAY INVISIBLE (-1985 4150);
FORCEPROP 1 LAST PACK_TYPE 0402LF
J 0
(-1985 4100);
DISPLAY 0.617021 (-1985 4100);
FORCEPROP 1 LAST TOLERANCE 1%
J 0
(-1980 4300);
DISPLAY 0.617021 (-1980 4300);
FORCEPROP 1 LAST VALUE 100K
J 0
(-1980 4350);
DISPLAY 0.617021 (-1980 4350);
FORCEPROP 1 LAST WATTAGE 1/16W
J 0
(-1985 4250);
DISPLAY 0.617021 (-1985 4250);
FORCEPROP 1 LAST MATERIAL CHIP
J 0
(-1985 4200);
DISPLAY 0.617021 (-1985 4200);
FORCEPROP 1 LAST $LOCATION R4680
J 0
(-1980 4400);
DISPLAY 0.978723 (-1980 4400);
FORCEPROP 1 LASTPIN (-2025 4375) $PN 1
J 0
(-2020 4337);
DISPLAY 0.787234 (-2020 4337);
PAINT MONO (-2020 4337);
FORCEPROP 1 LASTPIN (-2025 4175) $PN 2
J 0
(-2020 4185);
DISPLAY 0.787234 (-2020 4185);
PAINT MONO (-2020 4185);
FORCEPROP 2 LAST CDS_LIB pure_quanta
J 0
(-2025 4275);
DISPLAY INVISIBLE (-2025 4275);
FORCEPROP 1 LAST PATH I102
J 0
(-1975 4450);
DISPLAY 0.978723 (-1975 4450);
PAINT WHITE (-1975 4450);
DISPLAY INVISIBLE (-1975 4450);
FORCEPROP 2 LAST BOM_COST VR_SYSTEM 
J 0
(-1975 4450);
DISPLAY 0.680851 (-1975 4450);
DISPLAY INVISIBLE (-1975 4450);
FORCEPROP 2 LAST REUSE_ID 1
J 0
(-1975 4500);
DISPLAY 0.680851 (-1975 4500);
DISPLAY INVISIBLE (-1975 4500);
FORCEPROP 0 LAST CDS_LOCATION R4680
J 0
(-1975 4450);
DISPLAY 1.021277 (-1975 4450);
DISPLAY INVISIBLE (-1975 4450);
FORCEPROP 0 LAST $SEC 1
J 0
(-1975 4450);
DISPLAY 0.680851 (-1975 4450);
PAINT MONO (-1975 4450);
DISPLAY INVISIBLE (-1975 4450);
FORCEPROP 0 LAST CDS_SEC 1
J 0
(-1975 4450);
DISPLAY 1.021277 (-1975 4450);
DISPLAY INVISIBLE (-1975 4450);
FORCEADD UNIVERSAL_GND..1
(-1200 3300);
FORCEPROP 3 LASTPIN (-1200 3350) SIG_NAME GND\g
J 0
(-1190 3360);
DISPLAY 0.659574 (-1190 3360);
PAINT MONO (-1190 3360);
DISPLAY INVISIBLE (-1190 3360);
FORCEPROP 2 LAST BOM_COST VR_SYSTEM 
J 0
(-1500 3375);
DISPLAY 0.680851 (-1500 3375);
DISPLAY INVISIBLE (-1500 3375);
FORCEPROP 1 LAST HDL_POWER GND
J 1
(-1175 3225);
DISPLAY 0.872340 (-1175 3225);
PAINT GREEN (-1175 3225);
DISPLAY INVISIBLE (-1175 3225);
FORCEPROP 0 LAST VOLTAGE 0
J 0
(-1200 3300);
PAINT SKYBLUE (-1200 3300);
DISPLAY INVISIBLE (-1200 3300);
FORCEPROP 1 LAST PATH I103
J 0
(-1125 3300);
DISPLAY 0.872340 (-1125 3300);
PAINT AQUA (-1125 3300);
DISPLAY INVISIBLE (-1125 3300);
FORCEPROP 2 LAST CDS_LIB logical_power
J 0
(-1200 3300);
DISPLAY INVISIBLE (-1200 3300);
FORCEADD Q_RES..2
(-1200 4400);
FORCEPROP 1 LAST PART_NUMBER CS21002FB06
J 0
(-1160 4275);
DISPLAY 0.638298 (-1160 4275);
DISPLAY INVISIBLE (-1160 4275);
FORCEPROP 1 LAST VALUE 1K
J 0
(-1155 4475);
DISPLAY 0.638298 (-1155 4475);
FORCEPROP 1 LAST TOLERANCE 1%
J 0
(-1155 4425);
DISPLAY 0.638298 (-1155 4425);
FORCEPROP 1 LAST PACK_TYPE 0402LF
J 0
(-1160 4225);
DISPLAY 0.638298 (-1160 4225);
FORCEPROP 1 LAST MATERIAL CHIP
J 0
(-1160 4325);
DISPLAY 0.638298 (-1160 4325);
FORCEPROP 1 LAST WATTAGE 1/16W
J 0
(-1160 4375);
DISPLAY 0.638298 (-1160 4375);
FORCEPROP 1 LAST $LOCATION R4678
J 0
(-1155 4525);
DISPLAY 0.638298 (-1155 4525);
FORCEPROP 1 LASTPIN (-1200 4500) $PN 1
J 0
(-1195 4462);
DISPLAY 0.787234 (-1195 4462);
PAINT MONO (-1195 4462);
FORCEPROP 1 LASTPIN (-1200 4300) $PN 2
J 0
(-1195 4310);
DISPLAY 0.787234 (-1195 4310);
PAINT MONO (-1195 4310);
FORCEPROP 1 LAST PATH I104
J 0
(-1150 4575);
DISPLAY 0.978723 (-1150 4575);
PAINT WHITE (-1150 4575);
DISPLAY INVISIBLE (-1150 4575);
FORCEPROP 2 LAST REUSE_ID 3
J 0
(-1250 4600);
DISPLAY 0.680851 (-1250 4600);
DISPLAY INVISIBLE (-1250 4600);
FORCEPROP 2 LAST CDS_LIB pure_quanta
J 0
(-1200 4400);
PAINT MONO (-1200 4400);
DISPLAY INVISIBLE (-1200 4400);
FORCEPROP 2 LAST CDS_LOCATION R4678
J 0
(-1150 4625);
DISPLAY 1.021277 (-1150 4625);
DISPLAY INVISIBLE (-1150 4625);
FORCEPROP 0 LAST $SEC 1
J 0
(-1150 4575);
DISPLAY 0.680851 (-1150 4575);
PAINT MONO (-1150 4575);
DISPLAY INVISIBLE (-1150 4575);
FORCEPROP 2 LAST CDS_SEC 1
J 0
(-1150 4625);
DISPLAY 1.021277 (-1150 4625);
DISPLAY INVISIBLE (-1150 4625);
FORCEADD APX80929SAG7..1
R 2
(-6650 3200);
FORCEPROP 1 LAST PART_NUMBER AL080929000
J 2
(-6425 3467);
DISPLAY 0.723404 (-6425 3467);
PAINT GREEN (-6425 3467);
DISPLAY INVISIBLE (-6425 3467);
FORCEPROP 2 LAST VALUE APX809-29SAG-7
J 2
(-6425 3575);
DISPLAY 1.021277 (-6425 3575);
FORCEPROP 2 LAST PART_TYPE SMLF
J 2
(-6425 3625);
DISPLAY 1.021277 (-6425 3625);
FORCEPROP 1 LAST MATERIAL IC
J 2
(-6425 3410);
DISPLAY 0.723404 (-6425 3410);
PAINT GREEN (-6425 3410);
FORCEPROP 1 LAST $LOCATION U330
J 2
(-6425 3519);
DISPLAY 0.723404 (-6425 3519);
PAINT GREEN (-6425 3519);
FORCEPROP 2 LASTPIN (-6275 3300) $PN 1
J 0
(-6265 3310);
DISPLAY 0.808511 (-6265 3310);
FORCEPROP 2 LASTPIN (-6275 3100) $PN 2
J 0
(-6265 3110);
DISPLAY 0.808511 (-6265 3110);
FORCEPROP 2 LASTPIN (-7025 3200) $PN 3
J 2
(-7035 3210);
DISPLAY 0.808511 (-7035 3210);
FORCEPROP 1 LAST CDS_LMAN_SYM_OUTLINE -225,200,225,-200
J 2
(-6650 3200);
DISPLAY 0.468085 (-6650 3200);
PAINT GREEN (-6650 3200);
DISPLAY INVISIBLE (-6650 3200);
FORCEPROP 1 LAST NEEDS_NO_SIZE TRUE
J 2
(-6875 3040);
DISPLAY 0.723404 (-6875 3040);
PAINT GREEN (-6875 3040);
DISPLAY INVISIBLE (-6875 3040);
FORCEPROP 2 LAST CDS_LIB pure_quanta
J 2
(-6650 3200);
PAINT MONO (-6650 3200);
DISPLAY INVISIBLE (-6650 3200);
FORCEPROP 1 LAST PATH I105
J 2
(-6875 3000);
DISPLAY 0.723404 (-6875 3000);
PAINT GREEN (-6875 3000);
DISPLAY INVISIBLE (-6875 3000);
FORCEPROP 0 LAST CDS_LOCATION U330
J 0
(-6425 3675);
DISPLAY 1.021277 (-6425 3675);
DISPLAY INVISIBLE (-6425 3675);
FORCEPROP 2 LAST $SEC 1
J 0
(-6425 3675);
DISPLAY 0.680851 (-6425 3675);
PAINT MONO (-6425 3675);
DISPLAY INVISIBLE (-6425 3675);
FORCEPROP 2 LAST CDS_SEC 1
J 0
(-6425 3675);
DISPLAY 1.021277 (-6425 3675);
DISPLAY INVISIBLE (-6425 3675);
FORCEADD UNIVERSAL_GND..1
(-7200 2775);
FORCEPROP 3 LASTPIN (-7200 2825) SIG_NAME GND\g
J 0
(-7190 2835);
DISPLAY 0.659574 (-7190 2835);
PAINT MONO (-7190 2835);
DISPLAY INVISIBLE (-7190 2835);
FORCEPROP 1 LAST PATH I106
J 0
(-7125 2775);
DISPLAY 0.872340 (-7125 2775);
PAINT AQUA (-7125 2775);
DISPLAY INVISIBLE (-7125 2775);
FORCEPROP 1 LAST HDL_POWER GND
J 1
(-7175 2700);
DISPLAY 0.872340 (-7175 2700);
PAINT GREEN (-7175 2700);
DISPLAY INVISIBLE (-7175 2700);
FORCEPROP 2 LAST CDS_LIB logical_power
J 0
(-7200 2775);
PAINT MONO (-7200 2775);
DISPLAY INVISIBLE (-7200 2775);
FORCEADD Q_CAP..1
R 2
(-7200 3000);
FORCEPROP 1 LAST PART_NUMBER CH4104K1B00
J 2
(-7250 2850);
DISPLAY 0.510638 (-7250 2850);
DISPLAY INVISIBLE (-7250 2850);
FORCEPROP 1 LAST TOLERANCE 10%
J 2
(-7250 2950);
DISPLAY 0.510638 (-7250 2950);
FORCEPROP 1 LAST MATERIAL X7R
J 2
(-7250 2900);
DISPLAY 0.510638 (-7250 2900);
FORCEPROP 1 LAST VOLTAGE 25V
J 2
(-7250 3000);
DISPLAY 0.510638 (-7250 3000);
FORCEPROP 1 LAST VALUE 0.1UF
J 2
(-7250 3050);
DISPLAY 0.510638 (-7250 3050);
FORCEPROP 1 LAST PACK_TYPE 0402
J 2
(-7250 2800);
DISPLAY 0.510638 (-7250 2800);
FORCEPROP 1 LAST $LOCATION C2360
J 2
(-7250 3100);
DISPLAY 0.978723 (-7250 3100);
FORCEPROP 1 LASTPIN (-7200 3100) $PN 1
J 2
(-7210 3080);
DISPLAY 0.787234 (-7210 3080);
FORCEPROP 1 LASTPIN (-7200 2900) $PN 2
J 2
(-7210 2880);
DISPLAY 0.787234 (-7210 2880);
FORCEPROP 1 LAST PATH I107
J 2
(-7250 3150);
DISPLAY 0.978723 (-7250 3150);
PAINT WHITE (-7250 3150);
DISPLAY INVISIBLE (-7250 3150);
FORCEPROP 2 LAST CDS_LIB pure_quanta
J 2
(-7200 3000);
PAINT MONO (-7200 3000);
DISPLAY INVISIBLE (-7200 3000);
FORCEPROP 2 LAST CDS_LOCATION C2360
J 0
(-7250 3200);
DISPLAY 1.021277 (-7250 3200);
DISPLAY INVISIBLE (-7250 3200);
FORCEPROP 2 LAST $SEC 1
J 0
(-7250 3200);
DISPLAY 0.680851 (-7250 3200);
PAINT MONO (-7250 3200);
DISPLAY INVISIBLE (-7250 3200);
FORCEPROP 2 LAST CDS_SEC 1
J 0
(-7250 3200);
DISPLAY 1.021277 (-7250 3200);
DISPLAY INVISIBLE (-7250 3200);
FORCEADD UNIVERSAL_POWER..1
(-7200 3450);
FORCEPROP 3 LASTPIN (-7200 3400) SIG_NAME P3V3\g
J 0
(-7190 3410);
DISPLAY 0.659574 (-7190 3410);
PAINT MONO (-7190 3410);
DISPLAY INVISIBLE (-7190 3410);
FORCEPROP 1 LAST HDL_POWER P3V3
J 1
(-7200 3500);
DISPLAY 0.617021 (-7200 3500);
PAINT GREEN (-7200 3500);
FORCEPROP 2 LAST BOM_COST VR_SYSTEM 
J 0
(-7200 3550);
DISPLAY 0.680851 (-7200 3550);
DISPLAY INVISIBLE (-7200 3550);
FORCEPROP 1 LAST PATH I108
J 0
(-7150 3475);
DISPLAY 0.872340 (-7150 3475);
PAINT AQUA (-7150 3475);
DISPLAY INVISIBLE (-7150 3475);
FORCEPROP 2 LAST CDS_LIB logical_power
J 0
(-7200 3450);
DISPLAY INVISIBLE (-7200 3450);
FORCEADD Q_RES..2
(-5875 2900);
FORCEPROP 1 LAST PART_NUMBER CS41002FB09
J 0
(-5835 2775);
DISPLAY 0.638298 (-5835 2775);
DISPLAY INVISIBLE (-5835 2775);
FORCEPROP 1 LAST WATTAGE 1/16W
J 0
(-5835 2875);
DISPLAY 0.638298 (-5835 2875);
FORCEPROP 1 LAST MATERIAL CHIP
J 0
(-5835 2825);
DISPLAY 0.638298 (-5835 2825);
FORCEPROP 1 LAST VALUE 100K
J 0
(-5830 2975);
DISPLAY 0.638298 (-5830 2975);
FORCEPROP 1 LAST TOLERANCE 1%
J 0
(-5830 2925);
DISPLAY 0.638298 (-5830 2925);
FORCEPROP 1 LAST PACK_TYPE 0402LF
J 0
(-5835 2725);
DISPLAY 0.638298 (-5835 2725);
FORCEPROP 1 LAST $LOCATION R4681
J 0
(-5830 3025);
DISPLAY 0.978723 (-5830 3025);
FORCEPROP 1 LASTPIN (-5875 3000) $PN 1
J 0
(-5870 2962);
DISPLAY 0.787234 (-5870 2962);
PAINT MONO (-5870 2962);
FORCEPROP 1 LASTPIN (-5875 2800) $PN 2
J 0
(-5870 2810);
DISPLAY 0.787234 (-5870 2810);
PAINT MONO (-5870 2810);
FORCEPROP 1 LAST PATH I109
J 0
(-5825 3075);
DISPLAY 0.978723 (-5825 3075);
PAINT WHITE (-5825 3075);
DISPLAY INVISIBLE (-5825 3075);
FORCEPROP 2 LAST CDS_LIB pure_quanta
J 0
(-5875 2900);
DISPLAY INVISIBLE (-5875 2900);
FORCEPROP 0 LAST CDS_LOCATION R4681
J 0
(-5825 3075);
DISPLAY 1.021277 (-5825 3075);
DISPLAY INVISIBLE (-5825 3075);
FORCEPROP 0 LAST $SEC 1
J 0
(-5825 3075);
DISPLAY 0.680851 (-5825 3075);
PAINT MONO (-5825 3075);
DISPLAY INVISIBLE (-5825 3075);
FORCEPROP 0 LAST CDS_SEC 1
J 0
(-5825 3075);
DISPLAY 1.021277 (-5825 3075);
DISPLAY INVISIBLE (-5825 3075);
FORCEADD Q_CAP..1
R 2
(-5975 7550);
FORCEPROP 1 LAST PART_NUMBER CH4106K1B01
J 2
(-6025 7400);
DISPLAY 0.489362 (-6025 7400);
DISPLAY INVISIBLE (-6025 7400);
FORCEPROP 1 LAST TOLERANCE 10%
J 2
(-6025 7500);
DISPLAY 0.489362 (-6025 7500);
FORCEPROP 1 LAST VALUE 100NF
J 2
(-6025 7600);
DISPLAY 0.489362 (-6025 7600);
FORCEPROP 1 LAST VOLTAGE 50V
J 2
(-6025 7550);
DISPLAY 0.489362 (-6025 7550);
FORCEPROP 1 LAST MATERIAL X7R
J 2
(-6025 7450);
DISPLAY 0.489362 (-6025 7450);
FORCEPROP 1 LAST PACK_TYPE C0402
J 2
(-6025 7350);
DISPLAY 0.489362 (-6025 7350);
FORCEPROP 1 LAST $LOCATION C1042
J 2
(-6025 7650);
DISPLAY 0.978723 (-6025 7650);
FORCEPROP 1 LASTPIN (-5975 7650) $PN 1
J 2
(-5985 7630);
DISPLAY 0.787234 (-5985 7630);
FORCEPROP 1 LASTPIN (-5975 7450) $PN 2
J 2
(-5985 7430);
DISPLAY 0.787234 (-5985 7430);
FORCEPROP 1 LAST PATH I11
J 2
(-6025 7700);
DISPLAY 0.978723 (-6025 7700);
PAINT WHITE (-6025 7700);
DISPLAY INVISIBLE (-6025 7700);
FORCEPROP 2 LAST CDS_LIB pure_quanta
J 0
(-5975 7550);
PAINT MONO (-5975 7550);
DISPLAY INVISIBLE (-5975 7550);
FORCEPROP 2 LAST BOM_COST VR_SYSTEM 
J 0
(-6025 7700);
DISPLAY 0.680851 (-6025 7700);
DISPLAY INVISIBLE (-6025 7700);
FORCEPROP 2 LAST REUSE_ID 81
J 0
(-6025 7750);
DISPLAY 0.680851 (-6025 7750);
DISPLAY INVISIBLE (-6025 7750);
FORCEPROP 2 LAST CDS_LOCATION C1042
J 0
(-6025 7750);
DISPLAY 1.021277 (-6025 7750);
DISPLAY INVISIBLE (-6025 7750);
FORCEPROP 2 LAST $SEC 1
J 0
(-6025 7750);
DISPLAY 0.680851 (-6025 7750);
PAINT MONO (-6025 7750);
DISPLAY INVISIBLE (-6025 7750);
FORCEPROP 2 LAST CDS_SEC 1
J 0
(-6025 7750);
DISPLAY 1.021277 (-6025 7750);
DISPLAY INVISIBLE (-6025 7750);
FORCEADD UNIVERSAL_GND..1
(-5875 2525);
FORCEPROP 3 LASTPIN (-5875 2575) SIG_NAME GND\g
J 0
(-5865 2585);
DISPLAY 0.659574 (-5865 2585);
PAINT MONO (-5865 2585);
DISPLAY INVISIBLE (-5865 2585);
FORCEPROP 0 LAST VOLTAGE 0
J 0
(-5875 2525);
PAINT SKYBLUE (-5875 2525);
DISPLAY INVISIBLE (-5875 2525);
FORCEPROP 1 LAST HDL_POWER GND
J 1
(-5850 2450);
DISPLAY 0.872340 (-5850 2450);
PAINT GREEN (-5850 2450);
DISPLAY INVISIBLE (-5850 2450);
FORCEPROP 2 LAST BOM_COST VR_SYSTEM 
J 0
(-6175 2600);
DISPLAY 0.680851 (-6175 2600);
DISPLAY INVISIBLE (-6175 2600);
FORCEPROP 1 LAST PATH I110
J 0
(-5800 2525);
DISPLAY 0.872340 (-5800 2525);
PAINT AQUA (-5800 2525);
DISPLAY INVISIBLE (-5800 2525);
FORCEPROP 2 LAST CDS_LIB logical_power
J 0
(-5875 2525);
DISPLAY INVISIBLE (-5875 2525);
FORCEADD UNIVERSAL_POWER..1
(-2700 4300);
FORCEPROP 3 LASTPIN (-2700 4250) SIG_NAME P5V\g
J 0
(-2690 4260);
DISPLAY 0.659574 (-2690 4260);
PAINT MONO (-2690 4260);
DISPLAY INVISIBLE (-2690 4260);
FORCEPROP 1 LAST HDL_POWER P5V
J 1
(-2700 4350);
DISPLAY 0.617021 (-2700 4350);
PAINT GREEN (-2700 4350);
FORCEPROP 2 LAST CDS_LIB logical_power
J 0
(-2700 4300);
DISPLAY INVISIBLE (-2700 4300);
FORCEPROP 1 LAST PATH I111
J 0
(-2650 4325);
DISPLAY 0.872340 (-2650 4325);
PAINT AQUA (-2650 4325);
DISPLAY INVISIBLE (-2650 4325);
FORCEPROP 2 LAST BOM_COST VR_SYSTEM 
J 0
(-2700 4400);
DISPLAY 0.680851 (-2700 4400);
DISPLAY INVISIBLE (-2700 4400);
FORCEADD Q_RES..2
(-2625 3525);
FORCEPROP 1 LAST PART_NUMBER CS41002FB09
J 0
(-2585 3400);
DISPLAY 0.638298 (-2585 3400);
DISPLAY INVISIBLE (-2585 3400);
FORCEPROP 1 LAST TOLERANCE 1%
J 0
(-2580 3550);
DISPLAY 0.638298 (-2580 3550);
FORCEPROP 1 LAST WATTAGE 1/16W
J 0
(-2585 3500);
DISPLAY 0.638298 (-2585 3500);
FORCEPROP 1 LAST MATERIAL CHIP
J 0
(-2585 3450);
DISPLAY 0.638298 (-2585 3450);
FORCEPROP 1 LAST PACK_TYPE 0402LF
J 0
(-2585 3350);
DISPLAY 0.638298 (-2585 3350);
FORCEPROP 1 LAST VALUE 100K
J 0
(-2580 3600);
DISPLAY 0.638298 (-2580 3600);
FORCEPROP 1 LAST $LOCATION R4682
J 0
(-2580 3650);
DISPLAY 0.978723 (-2580 3650);
FORCEPROP 1 LASTPIN (-2625 3625) $PN 1
J 0
(-2620 3587);
DISPLAY 0.787234 (-2620 3587);
PAINT MONO (-2620 3587);
FORCEPROP 1 LASTPIN (-2625 3425) $PN 2
J 0
(-2620 3435);
DISPLAY 0.787234 (-2620 3435);
PAINT MONO (-2620 3435);
FORCEPROP 2 LAST CDS_LIB pure_quanta
J 0
(-2625 3525);
DISPLAY INVISIBLE (-2625 3525);
FORCEPROP 1 LAST PATH I112
J 0
(-2575 3700);
DISPLAY 0.978723 (-2575 3700);
PAINT WHITE (-2575 3700);
DISPLAY INVISIBLE (-2575 3700);
FORCEPROP 0 LAST CDS_LOCATION R4682
J 0
(-2575 3700);
DISPLAY 1.021277 (-2575 3700);
DISPLAY INVISIBLE (-2575 3700);
FORCEPROP 0 LAST $SEC 1
J 0
(-2575 3700);
DISPLAY 0.680851 (-2575 3700);
PAINT MONO (-2575 3700);
DISPLAY INVISIBLE (-2575 3700);
FORCEPROP 0 LAST CDS_SEC 1
J 0
(-2575 3700);
DISPLAY 1.021277 (-2575 3700);
DISPLAY INVISIBLE (-2575 3700);
FORCEADD UNIVERSAL_GND..1
(-2625 3150);
FORCEPROP 3 LASTPIN (-2625 3200) SIG_NAME GND\g
J 0
(-2615 3210);
DISPLAY 0.659574 (-2615 3210);
PAINT MONO (-2615 3210);
DISPLAY INVISIBLE (-2615 3210);
FORCEPROP 2 LAST CDS_LIB logical_power
J 0
(-2625 3150);
DISPLAY INVISIBLE (-2625 3150);
FORCEPROP 1 LAST PATH I113
J 0
(-2550 3150);
DISPLAY 0.872340 (-2550 3150);
PAINT AQUA (-2550 3150);
DISPLAY INVISIBLE (-2550 3150);
FORCEPROP 2 LAST BOM_COST VR_SYSTEM 
J 0
(-2925 3225);
DISPLAY 0.680851 (-2925 3225);
DISPLAY INVISIBLE (-2925 3225);
FORCEPROP 1 LAST HDL_POWER GND
J 1
(-2600 3075);
DISPLAY 0.872340 (-2600 3075);
PAINT GREEN (-2600 3075);
DISPLAY INVISIBLE (-2600 3075);
FORCEPROP 0 LAST VOLTAGE 0
J 0
(-2625 3150);
PAINT SKYBLUE (-2625 3150);
DISPLAY INVISIBLE (-2625 3150);
FORCEADD UNIVERSAL_POWER..1
(-5900 3675);
FORCEPROP 3 LASTPIN (-5900 3625) SIG_NAME P3V3\g
J 0
(-5890 3635);
DISPLAY 0.659574 (-5890 3635);
PAINT MONO (-5890 3635);
DISPLAY INVISIBLE (-5890 3635);
FORCEPROP 1 LAST HDL_POWER P3V3
J 1
(-5900 3725);
DISPLAY 0.617021 (-5900 3725);
PAINT GREEN (-5900 3725);
FORCEPROP 2 LAST CDS_LIB logical_power
J 0
(-5900 3675);
DISPLAY INVISIBLE (-5900 3675);
FORCEPROP 1 LAST PATH I114
J 0
(-5850 3700);
DISPLAY 0.872340 (-5850 3700);
PAINT AQUA (-5850 3700);
DISPLAY INVISIBLE (-5850 3700);
FORCEPROP 2 LAST BOM_COST VR_SYSTEM 
J 0
(-5900 3775);
DISPLAY 0.680851 (-5900 3775);
DISPLAY INVISIBLE (-5900 3775);
FORCEADD UNIVERSAL_GND..1
(-5975 7200);
FORCEPROP 3 LASTPIN (-5975 7250) SIG_NAME GND\g
J 0
(-5965 7260);
DISPLAY 0.659574 (-5965 7260);
PAINT MONO (-5965 7260);
DISPLAY INVISIBLE (-5965 7260);
FORCEPROP 1 LAST PATH I12
J 0
(-5900 7200);
DISPLAY 0.872340 (-5900 7200);
PAINT AQUA (-5900 7200);
DISPLAY INVISIBLE (-5900 7200);
FORCEPROP 0 LAST VOLTAGE 0
J 0
(-5975 7200);
PAINT SKYBLUE (-5975 7200);
DISPLAY INVISIBLE (-5975 7200);
FORCEPROP 2 LAST CDS_LIB logical_power
J 0
(-5975 7200);
DISPLAY INVISIBLE (-5975 7200);
FORCEPROP 1 LAST HDL_POWER GND
J 1
(-5950 7125);
DISPLAY 0.872340 (-5950 7125);
PAINT GREEN (-5950 7125);
DISPLAY INVISIBLE (-5950 7125);
FORCEPROP 2 LAST BOM_COST VR_SYSTEM 
J 0
(-6275 7275);
DISPLAY 0.680851 (-6275 7275);
DISPLAY INVISIBLE (-6275 7275);
FORCEADD UNIVERSAL_GND..1
(-5775 4275);
FORCEPROP 3 LASTPIN (-5775 4325) SIG_NAME GND\g
J 0
(-5765 4335);
DISPLAY 0.659574 (-5765 4335);
PAINT MONO (-5765 4335);
DISPLAY INVISIBLE (-5765 4335);
FORCEPROP 0 LAST VOLTAGE 0
J 0
(-5775 4275);
PAINT SKYBLUE (-5775 4275);
DISPLAY INVISIBLE (-5775 4275);
FORCEPROP 1 LAST HDL_POWER GND
J 1
(-5750 4200);
DISPLAY 0.872340 (-5750 4200);
PAINT GREEN (-5750 4200);
DISPLAY INVISIBLE (-5750 4200);
FORCEPROP 2 LAST BOM_COST VR_SYSTEM 
J 0
(-6075 4350);
DISPLAY 0.680851 (-6075 4350);
DISPLAY INVISIBLE (-6075 4350);
FORCEPROP 1 LAST PATH I13
J 0
(-5700 4275);
DISPLAY 0.872340 (-5700 4275);
PAINT AQUA (-5700 4275);
DISPLAY INVISIBLE (-5700 4275);
FORCEPROP 2 LAST CDS_LIB logical_power
J 0
(-5775 4275);
PAINT MONO (-5775 4275);
DISPLAY INVISIBLE (-5775 4275);
FORCEADD Q_RES..2
(-5775 4650);
FORCEPROP 1 LAST PART_NUMBER CS41002FB09
J 0
(-5735 4525);
DISPLAY 0.638298 (-5735 4525);
DISPLAY INVISIBLE (-5735 4525);
FORCEPROP 1 LAST WATTAGE 1/16W
J 0
(-5735 4625);
DISPLAY 0.638298 (-5735 4625);
FORCEPROP 1 LAST TOLERANCE 1%
J 0
(-5730 4675);
DISPLAY 0.638298 (-5730 4675);
FORCEPROP 1 LAST PACK_TYPE 0402LF
J 0
(-5735 4475);
DISPLAY 0.638298 (-5735 4475);
FORCEPROP 1 LAST VALUE 100K
J 0
(-5730 4725);
DISPLAY 0.638298 (-5730 4725);
FORCEPROP 1 LAST MATERIAL CHIP
J 0
(-5735 4575);
DISPLAY 0.638298 (-5735 4575);
FORCEPROP 1 LAST $LOCATION R1641
J 0
(-5730 4775);
DISPLAY 0.638298 (-5730 4775);
FORCEPROP 1 LASTPIN (-5775 4750) $PN 1
J 0
(-5770 4712);
DISPLAY 0.787234 (-5770 4712);
PAINT MONO (-5770 4712);
FORCEPROP 1 LASTPIN (-5775 4550) $PN 2
J 0
(-5770 4560);
DISPLAY 0.787234 (-5770 4560);
PAINT MONO (-5770 4560);
FORCEPROP 1 LAST PATH I14
J 0
(-5725 4825);
DISPLAY 0.978723 (-5725 4825);
PAINT WHITE (-5725 4825);
DISPLAY INVISIBLE (-5725 4825);
FORCEPROP 2 LAST CDS_LIB pure_quanta
J 0
(-5775 4650);
DISPLAY INVISIBLE (-5775 4650);
FORCEPROP 2 LAST CDS_LOCATION R1641
J 0
(-5725 4875);
DISPLAY 1.021277 (-5725 4875);
DISPLAY INVISIBLE (-5725 4875);
FORCEPROP 0 LAST $SEC 1
J 0
(-5725 4825);
DISPLAY 0.680851 (-5725 4825);
PAINT MONO (-5725 4825);
DISPLAY INVISIBLE (-5725 4825);
FORCEPROP 2 LAST CDS_SEC 1
J 0
(-5725 4875);
DISPLAY 1.021277 (-5725 4875);
DISPLAY INVISIBLE (-5725 4875);
FORCEADD UNIVERSAL_GND..1
(-5125 4500);
FORCEPROP 3 LASTPIN (-5125 4550) SIG_NAME GND\g
J 0
(-5115 4560);
DISPLAY 0.659574 (-5115 4560);
PAINT MONO (-5115 4560);
DISPLAY INVISIBLE (-5115 4560);
FORCEPROP 2 LAST CDS_LIB logical_power
J 0
(-5125 4500);
DISPLAY INVISIBLE (-5125 4500);
FORCEPROP 1 LAST PATH I15
J 0
(-5050 4500);
DISPLAY 0.872340 (-5050 4500);
PAINT AQUA (-5050 4500);
DISPLAY INVISIBLE (-5050 4500);
FORCEPROP 2 LAST BOM_COST VR_SYSTEM 
J 0
(-5425 4575);
DISPLAY 0.680851 (-5425 4575);
DISPLAY INVISIBLE (-5425 4575);
FORCEPROP 1 LAST HDL_POWER GND
J 1
(-5100 4425);
DISPLAY 0.872340 (-5100 4425);
PAINT GREEN (-5100 4425);
DISPLAY INVISIBLE (-5100 4425);
FORCEPROP 0 LAST VOLTAGE 0
J 0
(-5125 4500);
PAINT SKYBLUE (-5125 4500);
DISPLAY INVISIBLE (-5125 4500);
FORCEADD Q_RES..2
(-5125 5525);
FORCEPROP 1 LAST PART_NUMBER CS41002FB09
J 0
(-5085 5400);
DISPLAY 0.617021 (-5085 5400);
DISPLAY INVISIBLE (-5085 5400);
FORCEPROP 1 LAST WATTAGE 1/16W
J 0
(-5085 5500);
DISPLAY 0.617021 (-5085 5500);
FORCEPROP 1 LAST PACK_TYPE 0402LF
J 0
(-5085 5350);
DISPLAY 0.617021 (-5085 5350);
FORCEPROP 1 LAST TOLERANCE 1%
J 0
(-5080 5550);
DISPLAY 0.617021 (-5080 5550);
FORCEPROP 1 LAST VALUE 100K
J 0
(-5080 5600);
DISPLAY 0.617021 (-5080 5600);
FORCEPROP 1 LAST MATERIAL CHIP
J 0
(-5085 5450);
DISPLAY 0.617021 (-5085 5450);
FORCEPROP 1 LAST $LOCATION R1643
J 0
(-5080 5650);
DISPLAY 0.978723 (-5080 5650);
FORCEPROP 1 LASTPIN (-5125 5625) $PN 1
J 0
(-5120 5587);
DISPLAY 0.787234 (-5120 5587);
FORCEPROP 1 LASTPIN (-5125 5425) $PN 2
J 0
(-5120 5435);
DISPLAY 0.787234 (-5120 5435);
FORCEPROP 2 LAST CDS_LIB pure_quanta
J 0
(-5125 5525);
PAINT MONO (-5125 5525);
DISPLAY INVISIBLE (-5125 5525);
FORCEPROP 1 LAST PATH I17
J 0
(-5075 5700);
DISPLAY 0.978723 (-5075 5700);
PAINT WHITE (-5075 5700);
DISPLAY INVISIBLE (-5075 5700);
FORCEPROP 2 LAST REUSE_ID 1
J 0
(-5075 5750);
DISPLAY 0.680851 (-5075 5750);
DISPLAY INVISIBLE (-5075 5750);
FORCEPROP 2 LAST BOM_COST VR_SYSTEM 
J 0
(-5075 5700);
DISPLAY 0.680851 (-5075 5700);
DISPLAY INVISIBLE (-5075 5700);
FORCEPROP 2 LAST CDS_LOCATION R1643
J 0
(-5075 5750);
DISPLAY 1.021277 (-5075 5750);
DISPLAY INVISIBLE (-5075 5750);
FORCEPROP 2 LAST $SEC 1
J 0
(-5075 5750);
DISPLAY 0.680851 (-5075 5750);
PAINT MONO (-5075 5750);
DISPLAY INVISIBLE (-5075 5750);
FORCEPROP 2 LAST CDS_SEC 1
J 0
(-5075 5750);
DISPLAY 1.021277 (-5075 5750);
DISPLAY INVISIBLE (-5075 5750);
FORCEADD UNIVERSAL_POWER..1
(-5125 5800);
FORCEPROP 3 LASTPIN (-5125 5750) SIG_NAME P12V_AUX\g
J 0
(-5115 5760);
DISPLAY 0.659574 (-5115 5760);
PAINT MONO (-5115 5760);
DISPLAY INVISIBLE (-5115 5760);
FORCEPROP 1 LAST HDL_POWER P12V_AUX
J 1
(-5125 5850);
DISPLAY 0.617021 (-5125 5850);
PAINT GREEN (-5125 5850);
FORCEPROP 2 LAST CDS_LIB logical_power
J 0
(-5125 5800);
PAINT RED (-5125 5800);
DISPLAY INVISIBLE (-5125 5800);
FORCEPROP 1 LAST PATH I18
J 0
(-5075 5825);
DISPLAY 0.872340 (-5075 5825);
PAINT AQUA (-5075 5825);
DISPLAY INVISIBLE (-5075 5825);
FORCEPROP 2 LAST BOM_COST VR_SYSTEM 
J 0
(-5125 5900);
DISPLAY 0.680851 (-5125 5900);
DISPLAY INVISIBLE (-5125 5900);
FORCEADD Q_CAP..1
(-4075 3375);
FORCEPROP 1 LAST PART_NUMBER CH4106K1B01
J 0
(-4025 3250);
DISPLAY 0.617021 (-4025 3250);
DISPLAY INVISIBLE (-4025 3250);
FORCEPROP 1 LAST VOLTAGE 50V
J 0
(-4025 3400);
DISPLAY 0.617021 (-4025 3400);
FORCEPROP 1 LAST VALUE 100NF
J 0
(-4025 3450);
DISPLAY 0.617021 (-4025 3450);
FORCEPROP 1 LAST MATERIAL X7R
J 0
(-4025 3300);
DISPLAY 0.617021 (-4025 3300);
FORCEPROP 1 LAST TOLERANCE 10%
J 0
(-4025 3350);
DISPLAY 0.617021 (-4025 3350);
FORCEPROP 1 LAST PACK_TYPE C0402
J 0
(-4025 3200);
DISPLAY 0.617021 (-4025 3200);
FORCEPROP 1 LAST $LOCATION C1172
J 0
(-4025 3475);
DISPLAY 0.978723 (-4025 3475);
FORCEPROP 1 LASTPIN (-4075 3475) $PN 1
J 0
(-4065 3455);
DISPLAY 0.787234 (-4065 3455);
FORCEPROP 1 LASTPIN (-4075 3275) $PN 2
J 0
(-4065 3255);
DISPLAY 0.787234 (-4065 3255);
FORCEPROP 1 LAST PATH I2
J 0
(-4025 3525);
DISPLAY 0.978723 (-4025 3525);
PAINT WHITE (-4025 3525);
DISPLAY INVISIBLE (-4025 3525);
FORCEPROP 2 LAST CDS_LIB pure_quanta
J 0
(-4075 3375);
PAINT MONO (-4075 3375);
DISPLAY INVISIBLE (-4075 3375);
FORCEPROP 2 LAST BOM_COST VR_SYSTEM 
J 0
(-4025 3525);
DISPLAY 0.680851 (-4025 3525);
DISPLAY INVISIBLE (-4025 3525);
FORCEPROP 2 LAST CDS_LOCATION C1172
J 0
(-4025 3575);
DISPLAY 1.021277 (-4025 3575);
DISPLAY INVISIBLE (-4025 3575);
FORCEPROP 2 LAST $SEC 1
J 0
(-4025 3575);
DISPLAY 0.680851 (-4025 3575);
PAINT MONO (-4025 3575);
DISPLAY INVISIBLE (-4025 3575);
FORCEPROP 2 LAST CDS_SEC 1
J 0
(-4025 3575);
DISPLAY 1.021277 (-4025 3575);
DISPLAY INVISIBLE (-4025 3575);
FORCEADD UNIVERSAL_GND..1
(-4350 4750);
FORCEPROP 3 LASTPIN (-4350 4800) SIG_NAME GND\g
J 0
(-4340 4810);
DISPLAY 0.659574 (-4340 4810);
PAINT MONO (-4340 4810);
DISPLAY INVISIBLE (-4340 4810);
FORCEPROP 1 LAST PATH I20
J 0
(-4275 4750);
DISPLAY 0.872340 (-4275 4750);
PAINT AQUA (-4275 4750);
DISPLAY INVISIBLE (-4275 4750);
FORCEPROP 2 LAST BOM_COST VR_SYSTEM 
J 0
(-4650 4825);
DISPLAY 0.680851 (-4650 4825);
DISPLAY INVISIBLE (-4650 4825);
FORCEPROP 1 LAST HDL_POWER GND
J 1
(-4325 4675);
DISPLAY 0.872340 (-4325 4675);
PAINT GREEN (-4325 4675);
DISPLAY INVISIBLE (-4325 4675);
FORCEPROP 2 LAST CDS_LIB logical_power
J 0
(-4350 4750);
DISPLAY INVISIBLE (-4350 4750);
FORCEPROP 0 LAST VOLTAGE 0
J 0
(-4350 4750);
PAINT SKYBLUE (-4350 4750);
DISPLAY INVISIBLE (-4350 4750);
FORCEADD Q_RES..1
(-5575 6600);
FORCEPROP 1 LAST PART_NUMBER CS31002FB08
J 0
(-5450 6550);
DISPLAY 0.489362 (-5450 6550);
DISPLAY INVISIBLE (-5450 6550);
FORCEPROP 1 LAST WATTAGE 1/16W
J 2
(-5225 6500);
DISPLAY 0.489362 (-5225 6500);
FORCEPROP 1 LAST MATERIAL CHIP
J 0
(-5450 6500);
DISPLAY 0.489362 (-5450 6500);
FORCEPROP 1 LAST PACK_TYPE 0402LF
J 0
(-5275 6600);
DISPLAY 0.489362 (-5275 6600);
FORCEPROP 1 LAST VALUE 10K
J 2
(-5375 6600);
DISPLAY 0.489362 (-5375 6600);
FORCEPROP 1 LAST TOLERANCE 1%
J 0
(-5350 6600);
DISPLAY 0.489362 (-5350 6600);
FORCEPROP 1 LAST $LOCATION R1642
J 0
(-5850 6600);
DISPLAY 0.638298 (-5850 6600);
FORCEPROP 1 LASTPIN (-5675 6600) $PN 1
J 0
(-5663 6612);
DISPLAY 0.787234 (-5663 6612);
FORCEPROP 1 LASTPIN (-5475 6600) $PN 2
J 0
(-5513 6612);
DISPLAY 0.787234 (-5513 6612);
FORCEPROP 1 LAST PATH I22
J 0
(-5625 6750);
DISPLAY 0.978723 (-5625 6750);
PAINT WHITE (-5625 6750);
DISPLAY INVISIBLE (-5625 6750);
FORCEPROP 2 LAST CDS_LIB pure_quanta
J 0
(-5575 6600);
PAINT MONO (-5575 6600);
DISPLAY INVISIBLE (-5575 6600);
FORCEPROP 2 LAST BOM_COST VR_SYSTEM 
J 0
(-5775 6750);
DISPLAY 0.680851 (-5775 6750);
DISPLAY INVISIBLE (-5775 6750);
FORCEPROP 2 LAST REUSE_ID 3
J 0
(-5625 6800);
DISPLAY 0.680851 (-5625 6800);
DISPLAY INVISIBLE (-5625 6800);
FORCEPROP 2 LAST CDS_LOCATION R1642
J 0
(-5625 6800);
DISPLAY 1.021277 (-5625 6800);
DISPLAY INVISIBLE (-5625 6800);
FORCEPROP 2 LAST $SEC 1
J 0
(-5625 6800);
DISPLAY 0.680851 (-5625 6800);
PAINT MONO (-5625 6800);
DISPLAY INVISIBLE (-5625 6800);
FORCEPROP 2 LAST CDS_SEC 1
J 0
(-5625 6800);
DISPLAY 1.021277 (-5625 6800);
DISPLAY INVISIBLE (-5625 6800);
FORCEADD UNIVERSAL_POWER..1
(-5975 6900);
FORCEPROP 3 LASTPIN (-5975 6850) SIG_NAME P12V_AUX\g
J 0
(-5965 6860);
DISPLAY 0.659574 (-5965 6860);
PAINT MONO (-5965 6860);
DISPLAY INVISIBLE (-5965 6860);
FORCEPROP 1 LAST HDL_POWER P12V_AUX
J 1
(-5975 6950);
DISPLAY 0.617021 (-5975 6950);
PAINT GREEN (-5975 6950);
FORCEPROP 1 LAST PATH I23
J 0
(-5925 6925);
DISPLAY 0.872340 (-5925 6925);
PAINT AQUA (-5925 6925);
DISPLAY INVISIBLE (-5925 6925);
FORCEPROP 2 LAST CDS_LIB logical_power
J 0
(-5975 6900);
PAINT RED (-5975 6900);
DISPLAY INVISIBLE (-5975 6900);
FORCEPROP 2 LAST BOM_COST VR_SYSTEM 
J 0
(-5975 7000);
DISPLAY 0.680851 (-5975 7000);
DISPLAY INVISIBLE (-5975 7000);
FORCEADD Q_CAP..1
R 2
(-5650 7550);
FORCEPROP 1 LAST PART_NUMBER CH6103KEA00
J 2
(-5700 7400);
DISPLAY 0.489362 (-5700 7400);
DISPLAY INVISIBLE (-5700 7400);
FORCEPROP 1 LAST VALUE 10UF
J 2
(-5700 7600);
DISPLAY 0.489362 (-5700 7600);
FORCEPROP 1 LAST PACK_TYPE C0805
J 2
(-5700 7350);
DISPLAY 0.489362 (-5700 7350);
FORCEPROP 1 LAST MATERIAL X6S
J 2
(-5700 7450);
DISPLAY 0.489362 (-5700 7450);
FORCEPROP 1 LAST TOLERANCE 10%
J 2
(-5700 7500);
DISPLAY 0.489362 (-5700 7500);
FORCEPROP 1 LAST VOLTAGE 16V
J 2
(-5700 7550);
DISPLAY 0.489362 (-5700 7550);
FORCEPROP 1 LAST $LOCATION C1170
J 2
(-5700 7650);
DISPLAY 0.978723 (-5700 7650);
FORCEPROP 1 LASTPIN (-5650 7650) $PN 1
J 2
(-5660 7630);
DISPLAY 0.787234 (-5660 7630);
FORCEPROP 1 LASTPIN (-5650 7450) $PN 2
J 2
(-5660 7430);
DISPLAY 0.787234 (-5660 7430);
FORCEPROP 1 LAST PATH I24
J 2
(-5700 7700);
DISPLAY 0.978723 (-5700 7700);
PAINT WHITE (-5700 7700);
DISPLAY INVISIBLE (-5700 7700);
FORCEPROP 2 LAST CDS_LIB pure_quanta
J 0
(-5650 7550);
PAINT MONO (-5650 7550);
DISPLAY INVISIBLE (-5650 7550);
FORCEPROP 2 LAST BOM_COST VR_SYSTEM 
J 0
(-5700 7700);
DISPLAY 0.680851 (-5700 7700);
DISPLAY INVISIBLE (-5700 7700);
FORCEPROP 2 LAST REUSE_ID 6
J 0
(-5700 7750);
DISPLAY 0.680851 (-5700 7750);
DISPLAY INVISIBLE (-5700 7750);
FORCEPROP 2 LAST CDS_LOCATION C1170
J 0
(-5700 7750);
DISPLAY 1.021277 (-5700 7750);
DISPLAY INVISIBLE (-5700 7750);
FORCEPROP 2 LAST $SEC 1
J 0
(-5700 7750);
DISPLAY 0.680851 (-5700 7750);
PAINT MONO (-5700 7750);
DISPLAY INVISIBLE (-5700 7750);
FORCEPROP 2 LAST CDS_SEC 1
J 0
(-5700 7750);
DISPLAY 1.021277 (-5700 7750);
DISPLAY INVISIBLE (-5700 7750);
FORCEADD Q_CAP..1
R 2
(-5325 7550);
FORCEPROP 1 LAST PART_NUMBER CH6103KEA00
J 2
(-5375 7400);
DISPLAY 0.489362 (-5375 7400);
DISPLAY INVISIBLE (-5375 7400);
FORCEPROP 1 LAST TOLERANCE 10%
J 2
(-5375 7500);
DISPLAY 0.489362 (-5375 7500);
FORCEPROP 1 LAST MATERIAL EMPTY
J 2
(-5375 7450);
DISPLAY 0.489362 (-5375 7450);
PAINT RED (-5375 7450);
FORCEPROP 1 LAST VALUE 10UF
J 2
(-5375 7600);
DISPLAY 0.489362 (-5375 7600);
FORCEPROP 1 LAST VOLTAGE 16V
J 2
(-5375 7550);
DISPLAY 0.489362 (-5375 7550);
FORCEPROP 1 LAST PACK_TYPE C0805
J 2
(-5375 7350);
DISPLAY 0.489362 (-5375 7350);
FORCEPROP 1 LAST $LOCATION C1171
J 2
(-5375 7650);
DISPLAY 0.978723 (-5375 7650);
FORCEPROP 1 LASTPIN (-5325 7650) $PN 1
J 2
(-5335 7630);
DISPLAY 0.787234 (-5335 7630);
FORCEPROP 1 LASTPIN (-5325 7450) $PN 2
J 2
(-5335 7430);
DISPLAY 0.787234 (-5335 7430);
FORCEPROP 1 LAST PATH I25
J 2
(-5375 7700);
DISPLAY 0.978723 (-5375 7700);
PAINT WHITE (-5375 7700);
DISPLAY INVISIBLE (-5375 7700);
FORCEPROP 2 LAST CDS_LIB pure_quanta
J 0
(-5325 7550);
PAINT MONO (-5325 7550);
DISPLAY INVISIBLE (-5325 7550);
FORCEPROP 2 LAST BOM_COST VR_SYSTEM 
J 0
(-5375 7700);
DISPLAY 0.680851 (-5375 7700);
DISPLAY INVISIBLE (-5375 7700);
FORCEPROP 2 LAST REUSE_ID 8
J 0
(-5375 7750);
DISPLAY 0.680851 (-5375 7750);
DISPLAY INVISIBLE (-5375 7750);
FORCEPROP 2 LAST CDS_LOCATION C1171
J 0
(-5375 7750);
DISPLAY 1.021277 (-5375 7750);
DISPLAY INVISIBLE (-5375 7750);
FORCEPROP 2 LAST $SEC 1
J 0
(-5375 7750);
DISPLAY 0.680851 (-5375 7750);
PAINT MONO (-5375 7750);
DISPLAY INVISIBLE (-5375 7750);
FORCEPROP 2 LAST CDS_SEC 1
J 0
(-5375 7750);
DISPLAY 1.021277 (-5375 7750);
DISPLAY INVISIBLE (-5375 7750);
FORCEADD P1V0_AUX..1
(-5151 7849);
FORCEPROP 3 LASTPIN (-5151 7799) SIG_NAME P5V_AUX\g
J 0
(-5141 7809);
DISPLAY 0.659574 (-5141 7809);
PAINT MONO (-5141 7809);
DISPLAY INVISIBLE (-5141 7809);
FORCEPROP 1 LAST HDL_POWER P5V_AUX
J 1
(-5141 7889);
DISPLAY 0.617021 (-5141 7889);
PAINT GREEN (-5141 7889);
FORCEPROP 1 LAST PATH I26
J 0
(-5101 7874);
DISPLAY 0.872340 (-5101 7874);
PAINT AQUA (-5101 7874);
DISPLAY INVISIBLE (-5101 7874);
FORCEPROP 2 LAST CDS_LIB logical_power
J 0
(-5151 7849);
PAINT RED (-5151 7849);
DISPLAY INVISIBLE (-5151 7849);
FORCEPROP 2 LAST BOM_COST VR_SYSTEM 
J 0
(-5125 7925);
DISPLAY 0.680851 (-5125 7925);
DISPLAY INVISIBLE (-5125 7925);
FORCEADD Q_RES..2
(-4350 6300);
FORCEPROP 1 LAST PART_NUMBER CS21002FB06
J 2
(-4400 6175);
DISPLAY 0.617021 (-4400 6175);
DISPLAY INVISIBLE (-4400 6175);
FORCEPROP 1 LAST PACK_TYPE 0402LF
J 2
(-4400 6125);
DISPLAY 0.617021 (-4400 6125);
FORCEPROP 1 LAST MATERIAL CHIP
J 2
(-4400 6225);
DISPLAY 0.617021 (-4400 6225);
FORCEPROP 1 LAST WATTAGE 1/16W
J 2
(-4400 6275);
DISPLAY 0.617021 (-4400 6275);
FORCEPROP 1 LAST TOLERANCE 1%
J 2
(-4400 6325);
DISPLAY 0.617021 (-4400 6325);
FORCEPROP 1 LAST VALUE 1K
J 2
(-4400 6375);
DISPLAY 0.617021 (-4400 6375);
FORCEPROP 1 LAST $LOCATION R1654
J 0
(-4600 6425);
DISPLAY 0.978723 (-4600 6425);
FORCEPROP 1 LASTPIN (-4350 6400) $PN 1
J 0
(-4345 6362);
DISPLAY 0.787234 (-4345 6362);
FORCEPROP 1 LASTPIN (-4350 6200) $PN 2
J 0
(-4345 6210);
DISPLAY 0.787234 (-4345 6210);
FORCEPROP 2 LAST CDS_LIB pure_quanta
J 0
(-4350 6300);
PAINT MONO (-4350 6300);
DISPLAY INVISIBLE (-4350 6300);
FORCEPROP 2 LAST REUSE_ID 3
J 0
(-4400 6500);
DISPLAY 0.680851 (-4400 6500);
DISPLAY INVISIBLE (-4400 6500);
FORCEPROP 2 LAST BOM_COST VR_SYSTEM 
J 0
(-4400 6450);
DISPLAY 0.680851 (-4400 6450);
DISPLAY INVISIBLE (-4400 6450);
FORCEPROP 1 LAST PATH I27
J 0
(-4300 6475);
DISPLAY 0.978723 (-4300 6475);
PAINT WHITE (-4300 6475);
DISPLAY INVISIBLE (-4300 6475);
FORCEPROP 2 LAST CDS_LOCATION R1654
J 0
(-4300 6525);
DISPLAY 1.021277 (-4300 6525);
DISPLAY INVISIBLE (-4300 6525);
FORCEPROP 2 LAST $SEC 1
J 0
(-4300 6525);
DISPLAY 0.680851 (-4300 6525);
PAINT MONO (-4300 6525);
DISPLAY INVISIBLE (-4300 6525);
FORCEPROP 2 LAST CDS_SEC 1
J 0
(-4300 6525);
DISPLAY 1.021277 (-4300 6525);
DISPLAY INVISIBLE (-4300 6525);
FORCEADD UNIVERSAL_GND..1
(-3950 6025);
FORCEPROP 3 LASTPIN (-3950 6075) SIG_NAME GND\g
J 0
(-3940 6085);
DISPLAY 0.659574 (-3940 6085);
PAINT MONO (-3940 6085);
DISPLAY INVISIBLE (-3940 6085);
FORCEPROP 0 LAST VOLTAGE 0
J 0
(-3950 6025);
PAINT SKYBLUE (-3950 6025);
DISPLAY INVISIBLE (-3950 6025);
FORCEPROP 1 LAST HDL_POWER GND
J 1
(-3925 5950);
DISPLAY 0.872340 (-3925 5950);
PAINT GREEN (-3925 5950);
DISPLAY INVISIBLE (-3925 5950);
FORCEPROP 2 LAST BOM_COST VR_SYSTEM 
J 0
(-4250 6100);
DISPLAY 0.680851 (-4250 6100);
DISPLAY INVISIBLE (-4250 6100);
FORCEPROP 1 LAST PATH I28
J 0
(-3875 6025);
DISPLAY 0.872340 (-3875 6025);
PAINT AQUA (-3875 6025);
DISPLAY INVISIBLE (-3875 6025);
FORCEPROP 2 LAST CDS_LIB logical_power
J 0
(-3950 6025);
DISPLAY INVISIBLE (-3950 6025);
FORCEADD UNIVERSAL_POWER..1
(-4075 3950);
FORCEPROP 3 LASTPIN (-4075 3900) SIG_NAME P5V\g
J 0
(-4065 3910);
DISPLAY 0.659574 (-4065 3910);
PAINT MONO (-4065 3910);
DISPLAY INVISIBLE (-4065 3910);
FORCEPROP 1 LAST HDL_POWER P5V
J 1
(-4075 4000);
DISPLAY 0.617021 (-4075 4000);
PAINT GREEN (-4075 4000);
FORCEPROP 2 LAST BOM_COST VR_SYSTEM 
J 0
(-4075 4050);
DISPLAY 0.680851 (-4075 4050);
DISPLAY INVISIBLE (-4075 4050);
FORCEPROP 1 LAST PATH I3
J 0
(-4025 3975);
DISPLAY 0.872340 (-4025 3975);
PAINT AQUA (-4025 3975);
DISPLAY INVISIBLE (-4025 3975);
FORCEPROP 2 LAST CDS_LIB logical_power
J 0
(-4075 3950);
PAINT RED (-4075 3950);
DISPLAY INVISIBLE (-4075 3950);
FORCEADD MOSFET_NCH_1D3S..1
R 7
(-4000 6875);
FORCEPROP 1 LAST PART_NUMBER BAMNR580000
J 0
(-4200 7152);
DISPLAY 0.723404 (-4200 7152);
PAINT GREEN (-4200 7152);
DISPLAY INVISIBLE (-4200 7152);
FORCEPROP 2 LAST VALUE PSMNR58-30YLH
J 0
(-4200 7225);
DISPLAY 0.808511 (-4200 7225);
FORCEPROP 2 LAST PART_TYPE SMLF
J 0
(-4200 7300);
DISPLAY 0.808511 (-4200 7300);
FORCEPROP 1 LAST MATERIAL IC
J 0
(-4184 7102);
DISPLAY 0.723404 (-4184 7102);
PAINT GREEN (-4184 7102);
FORCEPROP 1 LAST LOCATION Q57
J 0
(-4168 7052);
DISPLAY 0.723404 (-4168 7052);
PAINT GREEN (-4168 7052);
FORCEPROP 2 LASTPIN (-3750 6975) $PN 1
J 0
(-3740 6985);
DISPLAY 0.808511 (-3740 6985);
FORCEPROP 2 LASTPIN (-3750 6875) $PN 2
J 0
(-3740 6885);
DISPLAY 0.808511 (-3740 6885);
FORCEPROP 2 LASTPIN (-3750 6775) $PN 3
J 0
(-3740 6785);
DISPLAY 0.808511 (-3740 6785);
FORCEPROP 2 LASTPIN (-3950 6675) $PN 4
R 1
J 2
(-3960 6665);
DISPLAY 0.808511 (-3960 6665);
FORCEPROP 2 LASTPIN (-4250 6875) $PN 5
J 2
(-4260 6885);
DISPLAY 0.808511 (-4260 6885);
FORCEPROP 1 LAST PATH I30
R 1
J 0
(-4000 6875);
DISPLAY 0.723404 (-4000 6875);
PAINT GREEN (-4000 6875);
DISPLAY INVISIBLE (-4000 6875);
FORCEPROP 2 LAST CDS_LIB pure_quanta
J 0
(-4000 6875);
PAINT MONO (-4000 6875);
DISPLAY INVISIBLE (-4000 6875);
FORCEPROP 1 LAST CDS_LMAN_SYM_OUTLINE -150,200,150,-200
R 1
J 0
(-4000 6875);
DISPLAY 0.468085 (-4000 6875);
PAINT GREEN (-4000 6875);
DISPLAY INVISIBLE (-4000 6875);
FORCEPROP 1 LAST NEEDS_NO_SIZE TRUE
R 1
J 0
(-4001 6875);
DISPLAY 0.468085 (-4001 6875);
PAINT GREEN (-4001 6875);
DISPLAY INVISIBLE (-4001 6875);
FORCEPROP 2 LAST $SEC 1
J 0
(-4200 7350);
DISPLAY 0.680851 (-4200 7350);
PAINT MONO (-4200 7350);
DISPLAY INVISIBLE (-4200 7350);
FORCEPROP 2 LAST CDS_SEC 1
J 0
(-4200 7350);
DISPLAY 1.021277 (-4200 7350);
DISPLAY INVISIBLE (-4200 7350);
FORCEADD UNIVERSAL_POWER..1
(-6625 2250);
FORCEPROP 3 LASTPIN (-6625 2200) SIG_NAME P3V3\g
J 0
(-6615 2210);
DISPLAY 0.659574 (-6615 2210);
PAINT MONO (-6615 2210);
DISPLAY INVISIBLE (-6615 2210);
FORCEPROP 1 LAST HDL_POWER P3V3
J 1
(-6625 2300);
DISPLAY 0.617021 (-6625 2300);
PAINT GREEN (-6625 2300);
FORCEPROP 2 LAST BOM_COST VR_SYSTEM 
J 0
(-6625 2350);
DISPLAY 0.680851 (-6625 2350);
DISPLAY INVISIBLE (-6625 2350);
FORCEPROP 1 LAST PATH I31
J 0
(-6575 2275);
DISPLAY 0.872340 (-6575 2275);
PAINT AQUA (-6575 2275);
DISPLAY INVISIBLE (-6575 2275);
FORCEPROP 2 LAST CDS_LIB logical_power
J 0
(-6625 2250);
PAINT RED (-6625 2250);
DISPLAY INVISIBLE (-6625 2250);
FORCEADD BAT547F..1
(-6175 1975);
FORCEPROP 1 LAST PART_NUMBER BC0BAT54Z53
J 0
(-6250 2110);
DISPLAY 0.617021 (-6250 2110);
PAINT GREEN (-6250 2110);
DISPLAY INVISIBLE (-6250 2110);
FORCEPROP 2 LAST PART_TYPE SMLF
J 0
(-6250 2275);
DISPLAY 0.680851 (-6250 2275);
PAINT GREEN (-6250 2275);
FORCEPROP 2 LAST VALUE BAT547F
J 0
(-6250 2225);
DISPLAY 0.617021 (-6250 2225);
PAINT GREEN (-6250 2225);
FORCEPROP 1 LAST MATERIAL IC
J 0
(-6250 2055);
DISPLAY 0.617021 (-6250 2055);
PAINT GREEN (-6250 2055);
FORCEPROP 1 LAST $LOCATION D7
J 0
(-6250 2135);
DISPLAY 0.723404 (-6250 2135);
PAINT GREEN (-6250 2135);
FORCEPROP 2 LASTPIN (-6300 1975) $PN 1
J 2
(-6310 1985);
DISPLAY 0.808511 (-6310 1985);
FORCEPROP 2 LASTPIN (-6050 1975) $PN 3
J 0
(-6040 1985);
DISPLAY 0.808511 (-6040 1985);
FORCEPROP 1 LAST PATH I32
J 0
(-6125 2030);
DISPLAY 0.723404 (-6125 2030);
PAINT GREEN (-6125 2030);
DISPLAY INVISIBLE (-6125 2030);
FORCEPROP 2 LAST CDS_LIB pure_quanta
J 0
(-6175 1975);
PAINT MONO (-6175 1975);
DISPLAY INVISIBLE (-6175 1975);
FORCEPROP 1 LAST CDS_LMAN_SYM_OUTLINE -25,50,25,-50
J 0
(-6175 1975);
DISPLAY 0.468085 (-6175 1975);
PAINT GREEN (-6175 1975);
DISPLAY INVISIBLE (-6175 1975);
FORCEPROP 2 LAST BOM_COST VR_SYSTEM 
J 0
(-6250 2275);
DISPLAY 0.680851 (-6250 2275);
DISPLAY INVISIBLE (-6250 2275);
FORCEPROP 1 LAST NEEDS_NO_SIZE TRUE
J 0
(-6175 1975);
DISPLAY 0.468085 (-6175 1975);
PAINT GREEN (-6175 1975);
DISPLAY INVISIBLE (-6175 1975);
FORCEPROP 1 LAST PIN_NAMES_ROTATE TRUE
J 0
(-6250 1900);
DISPLAY 0.234043 (-6250 1900);
PAINT GREEN (-6250 1900);
DISPLAY INVISIBLE (-6250 1900);
FORCEPROP 2 LAST CDS_LOCATION D7
J 0
(-6250 2325);
DISPLAY 1.021277 (-6250 2325);
DISPLAY INVISIBLE (-6250 2325);
FORCEPROP 2 LAST $SEC 1
J 0
(-6250 2325);
DISPLAY 0.680851 (-6250 2325);
PAINT MONO (-6250 2325);
DISPLAY INVISIBLE (-6250 2325);
FORCEPROP 2 LAST CDS_SEC 1
J 0
(-6250 2325);
DISPLAY 1.021277 (-6250 2325);
DISPLAY INVISIBLE (-6250 2325);
FORCEADD UNIVERSAL_POWER..1
(-5650 2250);
FORCEPROP 3 LASTPIN (-5650 2200) SIG_NAME P5V\g
J 0
(-5640 2210);
DISPLAY 0.659574 (-5640 2210);
PAINT MONO (-5640 2210);
DISPLAY INVISIBLE (-5640 2210);
FORCEPROP 1 LAST HDL_POWER P5V
J 1
(-5650 2300);
DISPLAY 0.617021 (-5650 2300);
PAINT GREEN (-5650 2300);
FORCEPROP 1 LAST PATH I34
J 0
(-5600 2275);
DISPLAY 0.872340 (-5600 2275);
PAINT AQUA (-5600 2275);
DISPLAY INVISIBLE (-5600 2275);
FORCEPROP 2 LAST BOM_COST VR_SYSTEM 
J 0
(-5650 2350);
DISPLAY 0.680851 (-5650 2350);
DISPLAY INVISIBLE (-5650 2350);
FORCEPROP 2 LAST CDS_LIB logical_power
J 0
(-5650 2250);
PAINT RED (-5650 2250);
DISPLAY INVISIBLE (-5650 2250);
FORCEADD RT9818C44GV..1
R 2
(-3400 3625);
FORCEPROP 1 LAST PART_NUMBER AL009818001
J 2
(-3172 3919);
DISPLAY 0.617021 (-3172 3919);
PAINT GREEN (-3172 3919);
DISPLAY INVISIBLE (-3172 3919);
FORCEPROP 1 LAST MATERIAL IC
J 2
(-3172 3830);
DISPLAY 0.617021 (-3172 3830);
PAINT GREEN (-3172 3830);
FORCEPROP 2 LAST PART_TYPE SMLF
J 2
(-3175 4100);
DISPLAY 0.680851 (-3175 4100);
PAINT GREEN (-3175 4100);
FORCEPROP 2 LAST VALUE RT9818C-44GV
J 2
(-3175 4050);
DISPLAY 0.617021 (-3175 4050);
PAINT GREEN (-3175 4050);
FORCEPROP 1 LAST $LOCATION U99
J 2
(-3172 4003);
DISPLAY 0.723404 (-3172 4003);
PAINT GREEN (-3172 4003);
FORCEPROP 2 LASTPIN (-3025 3525) $PN 2
J 0
(-3015 3535);
DISPLAY 0.808511 (-3015 3535);
FORCEPROP 2 LASTPIN (-3025 3725) $PN 1
J 0
(-3015 3735);
DISPLAY 0.808511 (-3015 3735);
FORCEPROP 2 LASTPIN (-3775 3625) $PN 3
J 2
(-3785 3635);
DISPLAY 0.808511 (-3785 3635);
FORCEPROP 1 LAST PATH I4
J 2
(-3400 3625);
DISPLAY 0.723404 (-3400 3625);
PAINT GREEN (-3400 3625);
DISPLAY INVISIBLE (-3400 3625);
FORCEPROP 2 LAST CDS_LIB pure_quanta
J 0
(-3400 3625);
PAINT MONO (-3400 3625);
DISPLAY INVISIBLE (-3400 3625);
FORCEPROP 1 LAST CDS_LMAN_SYM_OUTLINE -225,200,225,-200
J 2
(-3400 3625);
DISPLAY 0.468085 (-3400 3625);
PAINT GREEN (-3400 3625);
DISPLAY INVISIBLE (-3400 3625);
FORCEPROP 2 LAST BOM_COST VR_SYSTEM 
J 0
(-3175 4150);
DISPLAY 0.680851 (-3175 4150);
DISPLAY INVISIBLE (-3175 4150);
FORCEPROP 1 LAST PIN_NAMES_ROTATE TRUE
J 2
(-3400 3625);
DISPLAY 0.489362 (-3400 3625);
PAINT GREEN (-3400 3625);
DISPLAY INVISIBLE (-3400 3625);
FORCEPROP 2 LAST CDS_LOCATION U99
J 0
(-3175 4150);
DISPLAY 1.021277 (-3175 4150);
DISPLAY INVISIBLE (-3175 4150);
FORCEPROP 2 LAST $SEC 1
J 0
(-3175 4150);
DISPLAY 0.680851 (-3175 4150);
PAINT MONO (-3175 4150);
DISPLAY INVISIBLE (-3175 4150);
FORCEPROP 2 LAST CDS_SEC 1
J 0
(-3175 4150);
DISPLAY 1.021277 (-3175 4150);
DISPLAY INVISIBLE (-3175 4150);
FORCEADD UNIVERSAL_POWER..1
(-3475 7875);
FORCEPROP 3 LASTPIN (-3475 7825) SIG_NAME P5V\g
J 0
(-3465 7835);
DISPLAY 0.659574 (-3465 7835);
PAINT MONO (-3465 7835);
DISPLAY INVISIBLE (-3465 7835);
FORCEPROP 1 LAST HDL_POWER P5V
J 1
(-3475 7925);
DISPLAY 0.617021 (-3475 7925);
PAINT GREEN (-3475 7925);
FORCEPROP 1 LAST PATH I42
J 0
(-3425 7900);
DISPLAY 0.872340 (-3425 7900);
PAINT AQUA (-3425 7900);
DISPLAY INVISIBLE (-3425 7900);
FORCEPROP 2 LAST CDS_LIB logical_power
J 0
(-3475 7875);
PAINT RED (-3475 7875);
DISPLAY INVISIBLE (-3475 7875);
FORCEPROP 2 LAST BOM_COST VR_SYSTEM 
J 0
(-3475 7975);
DISPLAY 0.680851 (-3475 7975);
DISPLAY INVISIBLE (-3475 7975);
FORCEADD UNIVERSAL_GND..1
(-3375 7075);
FORCEPROP 3 LASTPIN (-3375 7125) SIG_NAME GND\g
J 0
(-3365 7135);
DISPLAY 0.659574 (-3365 7135);
PAINT MONO (-3365 7135);
DISPLAY INVISIBLE (-3365 7135);
FORCEPROP 1 LAST PATH I43
J 0
(-3300 7075);
DISPLAY 0.872340 (-3300 7075);
PAINT AQUA (-3300 7075);
DISPLAY INVISIBLE (-3300 7075);
FORCEPROP 0 LAST VOLTAGE 0
J 0
(-3375 7075);
PAINT SKYBLUE (-3375 7075);
DISPLAY INVISIBLE (-3375 7075);
FORCEPROP 2 LAST CDS_LIB logical_power
J 0
(-3375 7075);
DISPLAY INVISIBLE (-3375 7075);
FORCEPROP 1 LAST HDL_POWER GND
J 1
(-3350 7000);
DISPLAY 0.872340 (-3350 7000);
PAINT GREEN (-3350 7000);
DISPLAY INVISIBLE (-3350 7000);
FORCEPROP 2 LAST BOM_COST VR_SYSTEM 
J 0
(-3675 7150);
DISPLAY 0.680851 (-3675 7150);
DISPLAY INVISIBLE (-3675 7150);
FORCEADD Q_CAP..1
(-3375 7400);
FORCEPROP 1 LAST PART_NUMBER CH4106K1B01
J 0
(-3325 7250);
DISPLAY 0.489362 (-3325 7250);
DISPLAY INVISIBLE (-3325 7250);
FORCEPROP 1 LAST VALUE 100NF
J 0
(-3325 7450);
DISPLAY 0.489362 (-3325 7450);
FORCEPROP 1 LAST VOLTAGE 50V
J 0
(-3325 7400);
DISPLAY 0.489362 (-3325 7400);
FORCEPROP 1 LAST TOLERANCE 10%
J 0
(-3325 7350);
DISPLAY 0.489362 (-3325 7350);
FORCEPROP 1 LAST MATERIAL X7R
J 0
(-3325 7300);
DISPLAY 0.489362 (-3325 7300);
FORCEPROP 1 LAST PACK_TYPE C0402
J 0
(-3325 7200);
DISPLAY 0.489362 (-3325 7200);
FORCEPROP 1 LAST $LOCATION C1227
J 0
(-3325 7500);
DISPLAY 0.978723 (-3325 7500);
FORCEPROP 1 LASTPIN (-3375 7500) $PN 1
J 0
(-3365 7480);
DISPLAY 0.787234 (-3365 7480);
FORCEPROP 1 LASTPIN (-3375 7300) $PN 2
J 0
(-3365 7280);
DISPLAY 0.787234 (-3365 7280);
FORCEPROP 1 LAST PATH I44
J 0
(-3325 7550);
DISPLAY 0.978723 (-3325 7550);
PAINT WHITE (-3325 7550);
DISPLAY INVISIBLE (-3325 7550);
FORCEPROP 2 LAST CDS_LIB pure_quanta
J 0
(-3375 7400);
PAINT MONO (-3375 7400);
DISPLAY INVISIBLE (-3375 7400);
FORCEPROP 2 LAST BOM_COST VR_SYSTEM 
J 0
(-3325 7550);
DISPLAY 0.680851 (-3325 7550);
DISPLAY INVISIBLE (-3325 7550);
FORCEPROP 2 LAST REUSE_ID 81
J 0
(-3325 7600);
DISPLAY 0.680851 (-3325 7600);
DISPLAY INVISIBLE (-3325 7600);
FORCEPROP 2 LAST CDS_LOCATION C1227
J 0
(-3325 7600);
DISPLAY 1.021277 (-3325 7600);
DISPLAY INVISIBLE (-3325 7600);
FORCEPROP 2 LAST $SEC 1
J 0
(-3325 7600);
DISPLAY 0.680851 (-3325 7600);
PAINT MONO (-3325 7600);
DISPLAY INVISIBLE (-3325 7600);
FORCEPROP 2 LAST CDS_SEC 1
J 0
(-3325 7600);
DISPLAY 1.021277 (-3325 7600);
DISPLAY INVISIBLE (-3325 7600);
FORCEADD Q_CAP..1
(-3050 7400);
FORCEPROP 1 LAST PART_NUMBER CH6103KEA00
J 0
(-3000 7250);
DISPLAY 0.489362 (-3000 7250);
DISPLAY INVISIBLE (-3000 7250);
FORCEPROP 1 LAST TOLERANCE 10%
J 0
(-3000 7350);
DISPLAY 0.489362 (-3000 7350);
FORCEPROP 1 LAST MATERIAL X6S
J 0
(-3000 7300);
DISPLAY 0.489362 (-3000 7300);
FORCEPROP 1 LAST VOLTAGE 16V
J 0
(-3000 7400);
DISPLAY 0.489362 (-3000 7400);
FORCEPROP 1 LAST VALUE 10UF
J 0
(-3000 7450);
DISPLAY 0.489362 (-3000 7450);
FORCEPROP 1 LAST PACK_TYPE C0805
J 0
(-3000 7200);
DISPLAY 0.489362 (-3000 7200);
FORCEPROP 1 LAST $LOCATION C1331
J 0
(-3000 7500);
DISPLAY 0.978723 (-3000 7500);
FORCEPROP 1 LASTPIN (-3050 7500) $PN 1
J 0
(-3040 7480);
DISPLAY 0.787234 (-3040 7480);
FORCEPROP 1 LASTPIN (-3050 7300) $PN 2
J 0
(-3040 7280);
DISPLAY 0.787234 (-3040 7280);
FORCEPROP 1 LAST PATH I45
J 0
(-3000 7550);
DISPLAY 0.978723 (-3000 7550);
PAINT WHITE (-3000 7550);
DISPLAY INVISIBLE (-3000 7550);
FORCEPROP 2 LAST CDS_LIB pure_quanta
J 0
(-3050 7400);
PAINT MONO (-3050 7400);
DISPLAY INVISIBLE (-3050 7400);
FORCEPROP 2 LAST REUSE_ID 6
J 0
(-3000 7600);
DISPLAY 0.680851 (-3000 7600);
DISPLAY INVISIBLE (-3000 7600);
FORCEPROP 2 LAST BOM_COST VR_SYSTEM 
J 0
(-3000 7550);
DISPLAY 0.680851 (-3000 7550);
DISPLAY INVISIBLE (-3000 7550);
FORCEPROP 2 LAST CDS_LOCATION C1331
J 0
(-3000 7600);
DISPLAY 1.021277 (-3000 7600);
DISPLAY INVISIBLE (-3000 7600);
FORCEPROP 2 LAST $SEC 1
J 0
(-3000 7600);
DISPLAY 0.680851 (-3000 7600);
PAINT MONO (-3000 7600);
DISPLAY INVISIBLE (-3000 7600);
FORCEPROP 2 LAST CDS_SEC 1
J 0
(-3000 7600);
DISPLAY 1.021277 (-3000 7600);
DISPLAY INVISIBLE (-3000 7600);
FORCEADD UNIVERSAL_GND..1
(-1150 5225);
FORCEPROP 3 LASTPIN (-1150 5275) SIG_NAME GND\g
J 0
(-1140 5285);
DISPLAY 0.659574 (-1140 5285);
PAINT MONO (-1140 5285);
DISPLAY INVISIBLE (-1140 5285);
FORCEPROP 1 LAST PATH I47
J 0
(-1075 5225);
DISPLAY 0.872340 (-1075 5225);
PAINT AQUA (-1075 5225);
DISPLAY INVISIBLE (-1075 5225);
FORCEPROP 0 LAST VOLTAGE 0
J 0
(-1150 5225);
PAINT SKYBLUE (-1150 5225);
DISPLAY INVISIBLE (-1150 5225);
FORCEPROP 2 LAST CDS_LIB logical_power
J 0
(-1150 5225);
DISPLAY INVISIBLE (-1150 5225);
FORCEPROP 1 LAST HDL_POWER GND
J 1
(-1125 5150);
DISPLAY 0.872340 (-1125 5150);
PAINT GREEN (-1125 5150);
DISPLAY INVISIBLE (-1125 5150);
FORCEPROP 2 LAST BOM_COST VR_SYSTEM 
J 0
(-1450 5300);
DISPLAY 0.680851 (-1450 5300);
DISPLAY INVISIBLE (-1450 5300);
FORCEADD Q_CAP..1
R 2
(-1150 5550);
FORCEPROP 1 LAST PART_NUMBER CH4106K1B01
J 2
(-1200 5400);
DISPLAY 0.489362 (-1200 5400);
DISPLAY INVISIBLE (-1200 5400);
FORCEPROP 1 LAST PACK_TYPE C0402
J 2
(-1200 5350);
DISPLAY 0.489362 (-1200 5350);
FORCEPROP 1 LAST VALUE 100NF
J 2
(-1200 5600);
DISPLAY 0.489362 (-1200 5600);
FORCEPROP 1 LAST VOLTAGE 50V
J 2
(-1200 5550);
DISPLAY 0.489362 (-1200 5550);
FORCEPROP 1 LAST TOLERANCE 10%
J 2
(-1200 5500);
DISPLAY 0.489362 (-1200 5500);
FORCEPROP 1 LAST MATERIAL X7R
J 2
(-1200 5450);
DISPLAY 0.489362 (-1200 5450);
FORCEPROP 1 LAST $LOCATION C1332
J 2
(-1200 5650);
DISPLAY 0.978723 (-1200 5650);
FORCEPROP 1 LASTPIN (-1150 5650) $PN 1
J 2
(-1160 5630);
DISPLAY 0.787234 (-1160 5630);
FORCEPROP 1 LASTPIN (-1150 5450) $PN 2
J 2
(-1160 5430);
DISPLAY 0.787234 (-1160 5430);
FORCEPROP 1 LAST PATH I48
J 2
(-1200 5700);
DISPLAY 0.978723 (-1200 5700);
PAINT WHITE (-1200 5700);
DISPLAY INVISIBLE (-1200 5700);
FORCEPROP 2 LAST CDS_LIB pure_quanta
J 0
(-1150 5550);
PAINT MONO (-1150 5550);
DISPLAY INVISIBLE (-1150 5550);
FORCEPROP 2 LAST BOM_COST VR_SYSTEM 
J 0
(-1200 5700);
DISPLAY 0.680851 (-1200 5700);
DISPLAY INVISIBLE (-1200 5700);
FORCEPROP 2 LAST CDS_LOCATION C1332
J 0
(-1200 5750);
DISPLAY 1.021277 (-1200 5750);
DISPLAY INVISIBLE (-1200 5750);
FORCEPROP 2 LAST $SEC 1
J 0
(-1200 5750);
DISPLAY 0.680851 (-1200 5750);
PAINT MONO (-1200 5750);
DISPLAY INVISIBLE (-1200 5750);
FORCEPROP 2 LAST CDS_SEC 1
J 0
(-1200 5750);
DISPLAY 1.021277 (-1200 5750);
DISPLAY INVISIBLE (-1200 5750);
FORCEADD Q_CAP..1
R 2
(-825 5550);
FORCEPROP 1 LAST PART_NUMBER CH6103KEA00
J 2
(-875 5400);
DISPLAY 0.489362 (-875 5400);
DISPLAY INVISIBLE (-875 5400);
FORCEPROP 1 LAST PACK_TYPE C0805
J 2
(-875 5350);
DISPLAY 0.489362 (-875 5350);
FORCEPROP 1 LAST TOLERANCE 10%
J 2
(-875 5500);
DISPLAY 0.489362 (-875 5500);
FORCEPROP 1 LAST VOLTAGE 16V
J 2
(-875 5550);
DISPLAY 0.489362 (-875 5550);
FORCEPROP 1 LAST VALUE 10UF
J 2
(-875 5600);
DISPLAY 0.489362 (-875 5600);
FORCEPROP 1 LAST MATERIAL X6S
J 2
(-875 5450);
DISPLAY 0.489362 (-875 5450);
FORCEPROP 1 LAST $LOCATION C1333
J 2
(-875 5650);
DISPLAY 0.978723 (-875 5650);
FORCEPROP 1 LASTPIN (-825 5650) $PN 1
J 2
(-835 5630);
DISPLAY 0.787234 (-835 5630);
FORCEPROP 1 LASTPIN (-825 5450) $PN 2
J 2
(-835 5430);
DISPLAY 0.787234 (-835 5430);
FORCEPROP 1 LAST PATH I49
J 2
(-875 5700);
DISPLAY 0.978723 (-875 5700);
PAINT WHITE (-875 5700);
DISPLAY INVISIBLE (-875 5700);
FORCEPROP 2 LAST CDS_LIB pure_quanta
J 0
(-825 5550);
PAINT MONO (-825 5550);
DISPLAY INVISIBLE (-825 5550);
FORCEPROP 2 LAST BOM_COST VR_SYSTEM 
J 0
(-875 5700);
DISPLAY 0.680851 (-875 5700);
DISPLAY INVISIBLE (-875 5700);
FORCEPROP 2 LAST CDS_LOCATION C1333
J 0
(-875 5750);
DISPLAY 1.021277 (-875 5750);
DISPLAY INVISIBLE (-875 5750);
FORCEPROP 2 LAST $SEC 1
J 0
(-875 5750);
DISPLAY 0.680851 (-875 5750);
PAINT MONO (-875 5750);
DISPLAY INVISIBLE (-875 5750);
FORCEPROP 2 LAST CDS_SEC 1
J 0
(-875 5750);
DISPLAY 1.021277 (-875 5750);
DISPLAY INVISIBLE (-875 5750);
FORCEADD UNIVERSAL_GND..1
(-2800 3350);
FORCEPROP 3 LASTPIN (-2800 3400) SIG_NAME GND\g
J 0
(-2790 3410);
DISPLAY 0.659574 (-2790 3410);
PAINT MONO (-2790 3410);
DISPLAY INVISIBLE (-2790 3410);
FORCEPROP 1 LAST PATH I5
J 0
(-2725 3350);
DISPLAY 0.872340 (-2725 3350);
PAINT AQUA (-2725 3350);
DISPLAY INVISIBLE (-2725 3350);
FORCEPROP 2 LAST BOM_COST VR_SYSTEM 
J 0
(-3100 3425);
DISPLAY 0.680851 (-3100 3425);
DISPLAY INVISIBLE (-3100 3425);
FORCEPROP 1 LAST HDL_POWER GND
J 1
(-2775 3275);
DISPLAY 0.872340 (-2775 3275);
PAINT GREEN (-2775 3275);
DISPLAY INVISIBLE (-2775 3275);
FORCEPROP 2 LAST CDS_LIB logical_power
J 0
(-2800 3350);
DISPLAY INVISIBLE (-2800 3350);
FORCEPROP 0 LAST VOLTAGE 0
J 0
(-2800 3350);
PAINT SKYBLUE (-2800 3350);
DISPLAY INVISIBLE (-2800 3350);
FORCEADD Q_CAP..1
R 2
(-425 5550);
FORCEPROP 1 LAST PART_NUMBER CH6103KEA00
J 2
(-475 5400);
DISPLAY 0.489362 (-475 5400);
DISPLAY INVISIBLE (-475 5400);
FORCEPROP 1 LAST VOLTAGE 16V
J 2
(-475 5550);
DISPLAY 0.489362 (-475 5550);
FORCEPROP 1 LAST VALUE 10UF
J 2
(-475 5600);
DISPLAY 0.489362 (-475 5600);
FORCEPROP 1 LAST MATERIAL EMPTY
J 2
(-475 5450);
DISPLAY 0.489362 (-475 5450);
PAINT RED (-475 5450);
FORCEPROP 1 LAST PACK_TYPE C0805
J 2
(-475 5350);
DISPLAY 0.489362 (-475 5350);
FORCEPROP 1 LAST TOLERANCE 10%
J 2
(-475 5500);
DISPLAY 0.489362 (-475 5500);
FORCEPROP 1 LAST $LOCATION C1338
J 2
(-475 5650);
DISPLAY 0.978723 (-475 5650);
FORCEPROP 1 LASTPIN (-425 5650) $PN 1
J 2
(-435 5630);
DISPLAY 0.787234 (-435 5630);
FORCEPROP 1 LASTPIN (-425 5450) $PN 2
J 2
(-435 5430);
DISPLAY 0.787234 (-435 5430);
FORCEPROP 1 LAST PATH I50
J 2
(-475 5700);
DISPLAY 0.978723 (-475 5700);
PAINT WHITE (-475 5700);
DISPLAY INVISIBLE (-475 5700);
FORCEPROP 2 LAST CDS_LIB pure_quanta
J 0
(-425 5550);
PAINT MONO (-425 5550);
DISPLAY INVISIBLE (-425 5550);
FORCEPROP 2 LAST BOM_COST VR_SYSTEM 
J 0
(-475 5700);
DISPLAY 0.680851 (-475 5700);
DISPLAY INVISIBLE (-475 5700);
FORCEPROP 2 LAST CDS_LOCATION C1338
J 0
(-475 5750);
DISPLAY 1.021277 (-475 5750);
DISPLAY INVISIBLE (-475 5750);
FORCEPROP 2 LAST $SEC 1
J 0
(-475 5750);
DISPLAY 0.680851 (-475 5750);
PAINT MONO (-475 5750);
DISPLAY INVISIBLE (-475 5750);
FORCEPROP 2 LAST CDS_SEC 1
J 0
(-475 5750);
DISPLAY 1.021277 (-475 5750);
DISPLAY INVISIBLE (-475 5750);
FORCEADD MOSFET_NCH_1D3S..1
R 7
(125 4625);
FORCEPROP 1 LAST PART_NUMBER BAMNR580000
J 0
(-75 4902);
DISPLAY 0.723404 (-75 4902);
PAINT GREEN (-75 4902);
DISPLAY INVISIBLE (-75 4902);
FORCEPROP 2 LAST PART_TYPE SMLF
J 0
(-75 5050);
DISPLAY 0.808511 (-75 5050);
FORCEPROP 1 LAST MATERIAL IC
J 0
(-59 4852);
DISPLAY 0.723404 (-59 4852);
PAINT GREEN (-59 4852);
FORCEPROP 2 LAST VALUE PSMNR58-30YLH
J 0
(-75 4975);
DISPLAY 0.808511 (-75 4975);
FORCEPROP 1 LAST LOCATION Q56
J 0
(-43 4802);
DISPLAY 0.723404 (-43 4802);
PAINT GREEN (-43 4802);
FORCEPROP 2 LASTPIN (375 4725) $PN 1
J 0
(385 4735);
DISPLAY 0.808511 (385 4735);
FORCEPROP 2 LASTPIN (375 4625) $PN 2
J 0
(385 4635);
DISPLAY 0.808511 (385 4635);
FORCEPROP 2 LASTPIN (375 4525) $PN 3
J 0
(385 4535);
DISPLAY 0.808511 (385 4535);
FORCEPROP 2 LASTPIN (175 4425) $PN 4
R 1
J 2
(165 4415);
DISPLAY 0.808511 (165 4415);
FORCEPROP 2 LASTPIN (-125 4625) $PN 5
J 2
(-135 4635);
DISPLAY 0.808511 (-135 4635);
FORCEPROP 1 LAST PATH I51
R 1
J 0
(125 4625);
DISPLAY 0.723404 (125 4625);
PAINT GREEN (125 4625);
DISPLAY INVISIBLE (125 4625);
FORCEPROP 2 LAST CDS_LIB pure_quanta
J 0
(125 4625);
PAINT MONO (125 4625);
DISPLAY INVISIBLE (125 4625);
FORCEPROP 1 LAST CDS_LMAN_SYM_OUTLINE -150,200,150,-200
R 1
J 0
(125 4625);
DISPLAY 0.468085 (125 4625);
PAINT GREEN (125 4625);
DISPLAY INVISIBLE (125 4625);
FORCEPROP 1 LAST NEEDS_NO_SIZE TRUE
R 1
J 0
(124 4625);
DISPLAY 0.468085 (124 4625);
PAINT GREEN (124 4625);
DISPLAY INVISIBLE (124 4625);
FORCEPROP 2 LAST $SEC 1
J 0
(-75 5100);
DISPLAY 0.680851 (-75 5100);
PAINT MONO (-75 5100);
DISPLAY INVISIBLE (-75 5100);
FORCEPROP 2 LAST CDS_SEC 1
J 0
(-75 5100);
DISPLAY 1.021277 (-75 5100);
DISPLAY INVISIBLE (-75 5100);
FORCEADD P1V0_AUX..1
(-251 5949);
FORCEPROP 3 LASTPIN (-251 5899) SIG_NAME P3V3_AUX\g
J 0
(-241 5909);
DISPLAY 0.659574 (-241 5909);
PAINT MONO (-241 5909);
DISPLAY INVISIBLE (-241 5909);
FORCEPROP 1 LAST HDL_POWER P3V3_AUX
J 1
(-241 5989);
DISPLAY 0.617021 (-241 5989);
PAINT GREEN (-241 5989);
FORCEPROP 2 LAST BOM_COST VR_SYSTEM 
J 0
(-225 6025);
DISPLAY 0.680851 (-225 6025);
DISPLAY INVISIBLE (-225 6025);
FORCEPROP 1 LAST PATH I53
J 0
(-201 5974);
DISPLAY 0.872340 (-201 5974);
PAINT AQUA (-201 5974);
DISPLAY INVISIBLE (-201 5974);
FORCEPROP 2 LAST CDS_LIB logical_power
J 0
(-251 5949);
PAINT RED (-251 5949);
DISPLAY INVISIBLE (-251 5949);
FORCEADD Q_CAP..1
(775 5125);
FORCEPROP 1 LAST PART_NUMBER CH4106K1B01
J 0
(825 4975);
DISPLAY 0.489362 (825 4975);
DISPLAY INVISIBLE (825 4975);
FORCEPROP 1 LAST PACK_TYPE C0402
J 0
(825 4925);
DISPLAY 0.489362 (825 4925);
FORCEPROP 1 LAST MATERIAL X7R
J 0
(825 5025);
DISPLAY 0.489362 (825 5025);
FORCEPROP 1 LAST VALUE 100NF
J 0
(825 5175);
DISPLAY 0.489362 (825 5175);
FORCEPROP 1 LAST VOLTAGE 50V
J 0
(825 5125);
DISPLAY 0.489362 (825 5125);
FORCEPROP 1 LAST TOLERANCE 10%
J 0
(825 5075);
DISPLAY 0.489362 (825 5075);
FORCEPROP 1 LAST $LOCATION C1339
J 0
(825 5225);
DISPLAY 0.978723 (825 5225);
FORCEPROP 1 LASTPIN (775 5225) $PN 1
J 0
(785 5205);
DISPLAY 0.787234 (785 5205);
FORCEPROP 1 LASTPIN (775 5025) $PN 2
J 0
(785 5005);
DISPLAY 0.787234 (785 5005);
FORCEPROP 2 LAST BOM_COST VR_SYSTEM 
J 0
(825 5275);
DISPLAY 0.680851 (825 5275);
DISPLAY INVISIBLE (825 5275);
FORCEPROP 2 LAST CDS_LIB pure_quanta
J 0
(775 5125);
PAINT MONO (775 5125);
DISPLAY INVISIBLE (775 5125);
FORCEPROP 1 LAST PATH I58
J 0
(825 5275);
DISPLAY 0.978723 (825 5275);
PAINT WHITE (825 5275);
DISPLAY INVISIBLE (825 5275);
FORCEPROP 2 LAST CDS_LOCATION C1339
J 0
(825 5325);
DISPLAY 1.021277 (825 5325);
DISPLAY INVISIBLE (825 5325);
FORCEPROP 2 LAST $SEC 1
J 0
(825 5325);
DISPLAY 0.680851 (825 5325);
PAINT MONO (825 5325);
DISPLAY INVISIBLE (825 5325);
FORCEPROP 2 LAST CDS_SEC 1
J 0
(825 5325);
DISPLAY 1.021277 (825 5325);
DISPLAY INVISIBLE (825 5325);
FORCEADD UNIVERSAL_POWER..1
(675 5525);
FORCEPROP 3 LASTPIN (675 5475) SIG_NAME P3V3\g
J 0
(685 5485);
DISPLAY 0.659574 (685 5485);
PAINT MONO (685 5485);
DISPLAY INVISIBLE (685 5485);
FORCEPROP 1 LAST HDL_POWER P3V3
J 1
(675 5575);
DISPLAY 0.617021 (675 5575);
PAINT GREEN (675 5575);
FORCEPROP 2 LAST CDS_LIB logical_power
J 0
(675 5525);
PAINT RED (675 5525);
DISPLAY INVISIBLE (675 5525);
FORCEPROP 1 LAST PATH I59
J 0
(725 5550);
DISPLAY 0.872340 (725 5550);
PAINT AQUA (725 5550);
DISPLAY INVISIBLE (725 5550);
FORCEPROP 2 LAST BOM_COST VR_SYSTEM 
J 0
(675 5625);
DISPLAY 0.680851 (675 5625);
DISPLAY INVISIBLE (675 5625);
FORCEADD Q_RES..2
(-1200 4800);
FORCEPROP 1 LAST PART_NUMBER CS31002FB08
J 0
(-1160 4675);
DISPLAY 0.617021 (-1160 4675);
DISPLAY INVISIBLE (-1160 4675);
FORCEPROP 1 LAST TOLERANCE 1%
J 0
(-1155 4825);
DISPLAY 0.617021 (-1155 4825);
FORCEPROP 1 LAST VALUE 10K
J 0
(-1155 4875);
DISPLAY 0.617021 (-1155 4875);
FORCEPROP 1 LAST PACK_TYPE 0402LF
J 0
(-1160 4625);
DISPLAY 0.617021 (-1160 4625);
FORCEPROP 1 LAST WATTAGE 1/16W
J 0
(-1160 4775);
DISPLAY 0.617021 (-1160 4775);
FORCEPROP 1 LAST MATERIAL CHIP
J 0
(-1160 4725);
DISPLAY 0.617021 (-1160 4725);
FORCEPROP 1 LAST $LOCATION R1655
J 0
(-1155 4925);
DISPLAY 0.978723 (-1155 4925);
FORCEPROP 1 LASTPIN (-1200 4900) $PN 1
J 0
(-1195 4862);
DISPLAY 0.787234 (-1195 4862);
FORCEPROP 1 LASTPIN (-1200 4700) $PN 2
J 0
(-1195 4710);
DISPLAY 0.787234 (-1195 4710);
FORCEPROP 1 LAST PATH I6
J 0
(-1150 4975);
DISPLAY 0.978723 (-1150 4975);
PAINT WHITE (-1150 4975);
DISPLAY INVISIBLE (-1150 4975);
FORCEPROP 2 LAST CDS_LIB pure_quanta
J 0
(-1200 4800);
PAINT MONO (-1200 4800);
DISPLAY INVISIBLE (-1200 4800);
FORCEPROP 2 LAST CDS_LOCATION R1655
J 0
(-1150 5025);
DISPLAY 1.021277 (-1150 5025);
DISPLAY INVISIBLE (-1150 5025);
FORCEPROP 2 LAST $SEC 1
J 0
(-1150 5025);
DISPLAY 0.680851 (-1150 5025);
PAINT MONO (-1150 5025);
DISPLAY INVISIBLE (-1150 5025);
FORCEPROP 2 LAST CDS_SEC 1
J 0
(-1150 5025);
DISPLAY 1.021277 (-1150 5025);
DISPLAY INVISIBLE (-1150 5025);
FORCEADD UNIVERSAL_GND..1
(1150 4775);
FORCEPROP 3 LASTPIN (1150 4825) SIG_NAME GND\g
J 0
(1160 4835);
DISPLAY 0.659574 (1160 4835);
PAINT MONO (1160 4835);
DISPLAY INVISIBLE (1160 4835);
FORCEPROP 0 LAST VOLTAGE 0
J 0
(1150 4775);
PAINT SKYBLUE (1150 4775);
DISPLAY INVISIBLE (1150 4775);
FORCEPROP 2 LAST CDS_LIB logical_power
J 0
(1150 4775);
DISPLAY INVISIBLE (1150 4775);
FORCEPROP 1 LAST HDL_POWER GND
J 1
(1175 4700);
DISPLAY 0.872340 (1175 4700);
PAINT GREEN (1175 4700);
DISPLAY INVISIBLE (1175 4700);
FORCEPROP 2 LAST BOM_COST VR_SYSTEM 
J 0
(850 4850);
DISPLAY 0.680851 (850 4850);
DISPLAY INVISIBLE (850 4850);
FORCEPROP 1 LAST PATH I60
J 0
(1225 4775);
DISPLAY 0.872340 (1225 4775);
PAINT AQUA (1225 4775);
DISPLAY INVISIBLE (1225 4775);
FORCEADD Q_CAP..1
(1150 5125);
FORCEPROP 1 LAST PART_NUMBER CH6103KEA00
J 0
(1200 4975);
DISPLAY 0.489362 (1200 4975);
DISPLAY INVISIBLE (1200 4975);
FORCEPROP 1 LAST MATERIAL X6S
J 0
(1200 5025);
DISPLAY 0.489362 (1200 5025);
FORCEPROP 1 LAST PACK_TYPE C0805
J 0
(1200 4925);
DISPLAY 0.489362 (1200 4925);
FORCEPROP 1 LAST TOLERANCE 10%
J 0
(1200 5075);
DISPLAY 0.489362 (1200 5075);
FORCEPROP 1 LAST VOLTAGE 16V
J 0
(1200 5125);
DISPLAY 0.489362 (1200 5125);
FORCEPROP 1 LAST VALUE 10UF
J 0
(1200 5175);
DISPLAY 0.489362 (1200 5175);
FORCEPROP 1 LAST $LOCATION C1340
J 0
(1200 5225);
DISPLAY 0.978723 (1200 5225);
FORCEPROP 1 LASTPIN (1150 5225) $PN 1
J 0
(1160 5205);
DISPLAY 0.787234 (1160 5205);
FORCEPROP 1 LASTPIN (1150 5025) $PN 2
J 0
(1160 5005);
DISPLAY 0.787234 (1160 5005);
FORCEPROP 2 LAST BOM_COST VR_SYSTEM 
J 0
(1200 5275);
DISPLAY 0.680851 (1200 5275);
DISPLAY INVISIBLE (1200 5275);
FORCEPROP 2 LAST CDS_LIB pure_quanta
J 0
(1150 5125);
PAINT MONO (1150 5125);
DISPLAY INVISIBLE (1150 5125);
FORCEPROP 1 LAST PATH I61
J 0
(1200 5275);
DISPLAY 0.978723 (1200 5275);
PAINT WHITE (1200 5275);
DISPLAY INVISIBLE (1200 5275);
FORCEPROP 2 LAST CDS_LOCATION C1340
J 0
(1200 5325);
DISPLAY 1.021277 (1200 5325);
DISPLAY INVISIBLE (1200 5325);
FORCEPROP 2 LAST $SEC 1
J 0
(1200 5325);
DISPLAY 0.680851 (1200 5325);
PAINT MONO (1200 5325);
DISPLAY INVISIBLE (1200 5325);
FORCEPROP 2 LAST CDS_SEC 1
J 0
(1200 5325);
DISPLAY 1.021277 (1200 5325);
DISPLAY INVISIBLE (1200 5325);
FORCEADD OFFPAGE..2
(-4800 5125);
FORCEPROP 2 LAST $XR0 260 
J 0
(-4611 5125);
DISPLAY 0.638298 (-4611 5125);
PAINT MONO (-4611 5125);
FORCEPROP 1 LAST OFFPAGE TRUE
J 0
(-4475 5000);
DISPLAY 0.872340 (-4475 5000);
PAINT GREEN (-4475 5000);
DISPLAY INVISIBLE (-4475 5000);
FORCEPROP 1 LAST COMMENT_BODY TRUE
J 0
(-4845 5030);
DISPLAY 0.872340 (-4845 5030);
PAINT GREEN (-4845 5030);
DISPLAY INVISIBLE (-4845 5030);
FORCEPROP 2 LAST BOM_COST VR_SYSTEM 
J 0
(-5050 5175);
DISPLAY 0.829787 (-5050 5175);
PAINT PURPLE (-5050 5175);
DISPLAY INVISIBLE (-5050 5175);
FORCEPROP 2 LAST PATH I63
J 0
(-4625 5200);
DISPLAY 1.021277 (-4625 5200);
DISPLAY INVISIBLE (-4625 5200);
FORCEPROP 2 LAST CDS_LIB standard
J 0
(-4800 5125);
DISPLAY INVISIBLE (-4800 5125);
FORCEADD OFFPAGE..1
(-3125 6600);
FORCEPROP 2 LAST $XR0 260 
J 0
(-3377 6600);
DISPLAY 0.638298 (-3377 6600);
PAINT MONO (-3377 6600);
FORCEPROP 2 LAST CDS_LIB standard
J 0
(-3125 6600);
DISPLAY INVISIBLE (-3125 6600);
FORCEPROP 2 LAST PATH I64
J 0
(-3075 6675);
DISPLAY 1.021277 (-3075 6675);
DISPLAY INVISIBLE (-3075 6675);
FORCEPROP 2 LAST BOM_COST VR_SYSTEM 
J 0
(-3400 6650);
DISPLAY 0.617021 (-3400 6650);
PAINT PURPLE (-3400 6650);
DISPLAY INVISIBLE (-3400 6650);
FORCEPROP 1 LAST COMMENT_BODY TRUE
J 0
(-3000 6500);
DISPLAY 1.042553 (-3000 6500);
PAINT GREEN (-3000 6500);
DISPLAY INVISIBLE (-3000 6500);
FORCEPROP 1 LAST OFFPAGE TRUE
J 0
(-2800 6475);
DISPLAY 1.042553 (-2800 6475);
PAINT GREEN (-2800 6475);
DISPLAY INVISIBLE (-2800 6475);
FORCEADD UNIVERSAL_GND..1
(-2350 6225);
FORCEPROP 3 LASTPIN (-2350 6275) SIG_NAME GND\g
J 0
(-2340 6285);
DISPLAY 0.659574 (-2340 6285);
PAINT MONO (-2340 6285);
DISPLAY INVISIBLE (-2340 6285);
FORCEPROP 2 LAST CDS_LIB logical_power
J 0
(-2350 6225);
DISPLAY INVISIBLE (-2350 6225);
FORCEPROP 1 LAST PATH I65
J 0
(-2275 6225);
DISPLAY 0.872340 (-2275 6225);
PAINT AQUA (-2275 6225);
DISPLAY INVISIBLE (-2275 6225);
FORCEPROP 0 LAST VOLTAGE 0
J 0
(-2350 6225);
PAINT SKYBLUE (-2350 6225);
DISPLAY INVISIBLE (-2350 6225);
FORCEPROP 1 LAST HDL_POWER GND
J 1
(-2325 6150);
DISPLAY 0.872340 (-2325 6150);
PAINT GREEN (-2325 6150);
DISPLAY INVISIBLE (-2325 6150);
FORCEPROP 2 LAST BOM_COST VR_SYSTEM 
J 0
(-2650 6300);
DISPLAY 0.680851 (-2650 6300);
DISPLAY INVISIBLE (-2650 6300);
FORCEADD MOSFET_NCH_GDS_ESD_PROTECTED..1
(-2375 6600);
FORCEPROP 1 LAST PART_NUMBER BAM70020002
J 0
(-2233 6512);
DISPLAY 0.723404 (-2233 6512);
PAINT GREEN (-2233 6512);
DISPLAY INVISIBLE (-2233 6512);
FORCEPROP 2 LAST VALUE 2N7002K
J 0
(-2225 6650);
DISPLAY 0.680851 (-2225 6650);
FORCEPROP 1 LAST MATERIAL IC
J 0
(-2233 6455);
DISPLAY 0.723404 (-2233 6455);
PAINT GREEN (-2233 6455);
FORCEPROP 2 LAST PART_TYPE SMLF
J 0
(-2225 6700);
DISPLAY 0.680851 (-2225 6700);
FORCEPROP 1 LAST LOCATION U324
J 0
(-2233 6564);
DISPLAY 0.723404 (-2233 6564);
PAINT GREEN (-2233 6564);
FORCEPROP 0 LASTPIN (-2350 6800) $PN D
R 1
J 0
(-2360 6810);
DISPLAY 0.680851 (-2360 6810);
PAINT MONO (-2360 6810);
FORCEPROP 0 LASTPIN (-2550 6600) $PN G
J 2
(-2560 6610);
DISPLAY 0.680851 (-2560 6610);
PAINT MONO (-2560 6610);
FORCEPROP 0 LASTPIN (-2350 6400) $PN S
R 1
J 2
(-2360 6390);
DISPLAY 0.680851 (-2360 6390);
PAINT MONO (-2360 6390);
FORCEPROP 1 LAST NEEDS_NO_SIZE TRUE
J 0
(-2250 6490);
DISPLAY 0.723404 (-2250 6490);
PAINT GREEN (-2250 6490);
DISPLAY INVISIBLE (-2250 6490);
FORCEPROP 1 LAST CDS_LMAN_SYM_OUTLINE -125,150,125,-150
J 0
(-2375 6600);
DISPLAY 0.468085 (-2375 6600);
PAINT GREEN (-2375 6600);
DISPLAY INVISIBLE (-2375 6600);
FORCEPROP 1 LAST PATH I67
J 0
(-2250 6450);
DISPLAY 0.723404 (-2250 6450);
PAINT GREEN (-2250 6450);
DISPLAY INVISIBLE (-2250 6450);
FORCEPROP 2 LAST CDS_LIB pure_quanta
J 0
(-2375 6600);
DISPLAY INVISIBLE (-2375 6600);
FORCEPROP 0 LAST $SEC 1
J 0
(-2225 6750);
DISPLAY 0.680851 (-2225 6750);
PAINT MONO (-2225 6750);
DISPLAY INVISIBLE (-2225 6750);
FORCEPROP 0 LAST CDS_SEC 1
J 0
(-2225 6750);
DISPLAY 1.021277 (-2225 6750);
DISPLAY INVISIBLE (-2225 6750);
FORCEADD Q_CAP..1
(-3950 6300);
FORCEPROP 1 LAST PART_NUMBER CH4224K1B01
J 0
(-3900 6150);
DISPLAY 0.617021 (-3900 6150);
DISPLAY INVISIBLE (-3900 6150);
FORCEPROP 1 LAST MATERIAL X7R
J 0
(-3900 6200);
DISPLAY 0.617021 (-3900 6200);
FORCEPROP 1 LAST TOLERANCE 10%
J 0
(-3900 6250);
DISPLAY 0.617021 (-3900 6250);
FORCEPROP 1 LAST PACK_TYPE C0402
J 0
(-3900 6100);
DISPLAY 0.617021 (-3900 6100);
FORCEPROP 1 LAST VALUE 0.22UF
J 0
(-3900 6350);
DISPLAY 0.617021 (-3900 6350);
FORCEPROP 1 LAST VOLTAGE 25V
J 0
(-3900 6300);
DISPLAY 0.617021 (-3900 6300);
FORCEPROP 1 LAST LOCATION C1226
J 0
(-3900 6400);
DISPLAY 0.617021 (-3900 6400);
FORCEPROP 1 LASTPIN (-3950 6400) $PN 1
J 0
(-3940 6380);
DISPLAY 0.787234 (-3940 6380);
PAINT MONO (-3940 6380);
FORCEPROP 1 LASTPIN (-3950 6200) $PN 2
J 0
(-3940 6180);
DISPLAY 0.787234 (-3940 6180);
PAINT MONO (-3940 6180);
FORCEPROP 1 LAST PATH I68
J 0
(-3900 6450);
DISPLAY 0.978723 (-3900 6450);
PAINT WHITE (-3900 6450);
DISPLAY INVISIBLE (-3900 6450);
FORCEPROP 2 LAST CDS_LIB pure_quanta
J 0
(-3950 6300);
DISPLAY INVISIBLE (-3950 6300);
FORCEPROP 0 LAST $SEC 1
J 0
(-3900 6450);
DISPLAY 0.680851 (-3900 6450);
PAINT MONO (-3900 6450);
DISPLAY INVISIBLE (-3900 6450);
FORCEPROP 0 LAST CDS_SEC 1
J 0
(-3900 6450);
DISPLAY 1.021277 (-3900 6450);
DISPLAY INVISIBLE (-3900 6450);
FORCEADD MOSFET_NCH_DUAL..1
(-5175 4975);
FORCEPROP 1 LAST PART_NUMBER BAM138K0003
J 0
(-5024 4889);
DISPLAY 0.723404 (-5024 4889);
PAINT GREEN (-5024 4889);
DISPLAY INVISIBLE (-5024 4889);
FORCEPROP 2 LAST PART_TYPE SMLF
J 0
(-5000 5050);
DISPLAY 1.021277 (-5000 5050);
FORCEPROP 1 LAST MATERIAL IC
J 0
(-5024 4824);
DISPLAY 0.723404 (-5024 4824);
PAINT GREEN (-5024 4824);
FORCEPROP 2 LAST VALUE PJT138K
J 0
(-5000 5000);
DISPLAY 1.021277 (-5000 5000);
FORCEPROP 1 LAST LOCATION Q37
J 0
(-5024 4949);
DISPLAY 0.723404 (-5024 4949);
PAINT GREEN (-5024 4949);
FORCEPROP 2 LASTPIN (-5125 5175) $PN 6
R 1
J 0
(-5135 5185);
DISPLAY 0.680851 (-5135 5185);
PAINT MONO (-5135 5185);
FORCEPROP 2 LASTPIN (-5375 4925) $PN 2
J 2
(-5385 4935);
DISPLAY 0.680851 (-5385 4935);
PAINT MONO (-5385 4935);
FORCEPROP 2 LASTPIN (-5125 4775) $PN 1
R 1
J 2
(-5135 4765);
DISPLAY 0.680851 (-5135 4765);
PAINT MONO (-5135 4765);
FORCEPROP 2 LAST CDS_LIB pure_quanta
J 0
(-5175 4975);
DISPLAY INVISIBLE (-5175 4975);
FORCEPROP 1 LAST CDS_LMAN_SYM_OUTLINE -150,150,150,-150
J 0
(-5175 4975);
DISPLAY 0.468085 (-5175 4975);
PAINT GREEN (-5175 4975);
DISPLAY INVISIBLE (-5175 4975);
FORCEPROP 2 LAST SEC_TYPE 
J 0
(-5000 5100);
DISPLAY 1.021277 (-5000 5100);
DISPLAY INVISIBLE (-5000 5100);
FORCEPROP 1 LAST PATH I69
J 0
(-5175 4975);
DISPLAY 0.723404 (-5175 4975);
PAINT GREEN (-5175 4975);
DISPLAY INVISIBLE (-5175 4975);
FORCEPROP 1 LAST NEEDS_NO_SIZE TRUE
J 0
(-5175 4974);
DISPLAY 0.468085 (-5175 4974);
PAINT GREEN (-5175 4974);
DISPLAY INVISIBLE (-5175 4974);
FORCEPROP 2 LAST SEC 1
J 0
(-5000 5100);
DISPLAY 0.680851 (-5000 5100);
PAINT MONO (-5000 5100);
DISPLAY INVISIBLE (-5000 5100);
FORCEADD OFFPAGE..1
(-7125 4700);
FORCEPROP 2 LAST $XR0 214 
J 0
(-7377 4700);
DISPLAY 0.638298 (-7377 4700);
PAINT MONO (-7377 4700);
FORCEPROP 1 LAST OFFPAGE TRUE
J 0
(-6800 4575);
DISPLAY 1.042553 (-6800 4575);
PAINT GREEN (-6800 4575);
DISPLAY INVISIBLE (-6800 4575);
FORCEPROP 1 LAST COMMENT_BODY TRUE
J 0
(-7000 4600);
DISPLAY 1.042553 (-7000 4600);
PAINT GREEN (-7000 4600);
DISPLAY INVISIBLE (-7000 4600);
FORCEPROP 2 LAST BOM_COST VR_SYSTEM 
J 0
(-7400 4750);
DISPLAY 0.617021 (-7400 4750);
PAINT PURPLE (-7400 4750);
DISPLAY INVISIBLE (-7400 4750);
FORCEPROP 2 LAST PATH I7
J 0
(-7375 4750);
DISPLAY 1.021277 (-7375 4750);
DISPLAY INVISIBLE (-7375 4750);
FORCEPROP 2 LAST CDS_LIB standard
J 0
(-7125 4700);
DISPLAY INVISIBLE (-7125 4700);
FORCEADD MOSFET_NCH_DUAL..2
(-4400 5300);
FORCEPROP 1 LAST PART_NUMBER BAM138K0003
J 0
(-4249 5206);
DISPLAY 0.723404 (-4249 5206);
PAINT GREEN (-4249 5206);
DISPLAY INVISIBLE (-4249 5206);
FORCEPROP 1 LAST MATERIAL IC
J 0
(-4249 5151);
DISPLAY 0.723404 (-4249 5151);
PAINT GREEN (-4249 5151);
FORCEPROP 2 LAST VALUE PJT138K
J 0
(-4225 5325);
DISPLAY 1.021277 (-4225 5325);
FORCEPROP 2 LAST PART_TYPE SMLF
J 0
(-4225 5375);
DISPLAY 1.021277 (-4225 5375);
FORCEPROP 1 LAST LOCATION Q37
J 0
(-4249 5276);
DISPLAY 0.723404 (-4249 5276);
PAINT GREEN (-4249 5276);
FORCEPROP 0 LASTPIN (-4350 5500) $PN 3
R 1
J 0
(-4360 5510);
DISPLAY 0.680851 (-4360 5510);
PAINT MONO (-4360 5510);
FORCEPROP 0 LASTPIN (-4600 5250) $PN 5
J 2
(-4610 5260);
DISPLAY 0.680851 (-4610 5260);
PAINT MONO (-4610 5260);
FORCEPROP 0 LASTPIN (-4350 5100) $PN 4
R 1
J 2
(-4360 5090);
DISPLAY 0.680851 (-4360 5090);
PAINT MONO (-4360 5090);
FORCEPROP 2 LAST CDS_LIB pure_quanta
J 0
(-4400 5300);
DISPLAY INVISIBLE (-4400 5300);
FORCEPROP 1 LAST CDS_LMAN_SYM_OUTLINE -150,150,150,-150
J 0
(-4400 5300);
DISPLAY 0.468085 (-4400 5300);
PAINT GREEN (-4400 5300);
DISPLAY INVISIBLE (-4400 5300);
FORCEPROP 1 LAST PATH I76
J 0
(-4250 5150);
DISPLAY 0.723404 (-4250 5150);
PAINT GREEN (-4250 5150);
DISPLAY INVISIBLE (-4250 5150);
FORCEPROP 1 LAST NEEDS_NO_SIZE TRUE
J 0
(-4250 5191);
DISPLAY 0.468085 (-4250 5191);
PAINT GREEN (-4250 5191);
DISPLAY INVISIBLE (-4250 5191);
FORCEPROP 0 LAST $SEC 2
J 0
(-4225 5425);
DISPLAY 0.680851 (-4225 5425);
PAINT MONO (-4225 5425);
DISPLAY INVISIBLE (-4225 5425);
FORCEPROP 0 LAST CDS_SEC 2
J 0
(-4225 5425);
DISPLAY 1.021277 (-4225 5425);
DISPLAY INVISIBLE (-4225 5425);
FORCEADD Q_RES..2
(-2350 7225);
FORCEPROP 1 LAST PART_NUMBER CS12436F201
J 0
(-2310 7100);
DISPLAY 0.638298 (-2310 7100);
DISPLAY INVISIBLE (-2310 7100);
FORCEPROP 1 LAST PACK_TYPE 1206LF
J 0
(-2310 7050);
DISPLAY 0.638298 (-2310 7050);
FORCEPROP 1 LAST VALUE 243
J 0
(-2305 7300);
DISPLAY 0.638298 (-2305 7300);
FORCEPROP 1 LAST TOLERANCE 1%
J 0
(-2305 7250);
DISPLAY 0.638298 (-2305 7250);
FORCEPROP 1 LAST WATTAGE 1/4W
J 0
(-2310 7200);
DISPLAY 0.638298 (-2310 7200);
FORCEPROP 1 LAST MATERIAL CHIP
J 0
(-2310 7150);
DISPLAY 0.638298 (-2310 7150);
FORCEPROP 1 LAST LOCATION R4638
J 0
(-2305 7350);
DISPLAY 0.638298 (-2305 7350);
FORCEPROP 1 LASTPIN (-2350 7325) $PN 1
J 0
(-2345 7287);
DISPLAY 0.787234 (-2345 7287);
PAINT MONO (-2345 7287);
FORCEPROP 1 LASTPIN (-2350 7125) $PN 2
J 0
(-2345 7135);
DISPLAY 0.787234 (-2345 7135);
PAINT MONO (-2345 7135);
FORCEPROP 2 LAST CDS_LIB pure_quanta
J 0
(-2350 7225);
DISPLAY INVISIBLE (-2350 7225);
FORCEPROP 1 LAST PATH I77
J 0
(-2300 7400);
DISPLAY 0.978723 (-2300 7400);
PAINT WHITE (-2300 7400);
DISPLAY INVISIBLE (-2300 7400);
FORCEPROP 0 LAST $SEC 1
J 0
(-2300 7400);
DISPLAY 0.680851 (-2300 7400);
PAINT MONO (-2300 7400);
DISPLAY INVISIBLE (-2300 7400);
FORCEPROP 0 LAST CDS_SEC 1
J 0
(-2300 7400);
DISPLAY 1.021277 (-2300 7400);
DISPLAY INVISIBLE (-2300 7400);
FORCEADD Q_RES..2
(-1800 7225);
FORCEPROP 1 LAST PART_NUMBER CS12436F201
J 0
(-1760 7100);
DISPLAY 0.638298 (-1760 7100);
DISPLAY INVISIBLE (-1760 7100);
FORCEPROP 1 LAST PACK_TYPE 1206LF
J 0
(-1760 7050);
DISPLAY 0.638298 (-1760 7050);
FORCEPROP 1 LAST MATERIAL CHIP
J 0
(-1760 7150);
DISPLAY 0.638298 (-1760 7150);
FORCEPROP 1 LAST VALUE 243
J 0
(-1755 7300);
DISPLAY 0.638298 (-1755 7300);
FORCEPROP 1 LAST TOLERANCE 1%
J 0
(-1755 7250);
DISPLAY 0.638298 (-1755 7250);
FORCEPROP 1 LAST WATTAGE 1/4W
J 0
(-1760 7200);
DISPLAY 0.638298 (-1760 7200);
FORCEPROP 1 LAST LOCATION R4639
J 0
(-1755 7350);
DISPLAY 0.638298 (-1755 7350);
FORCEPROP 1 LASTPIN (-1800 7325) $PN 1
J 0
(-1795 7287);
DISPLAY 0.787234 (-1795 7287);
PAINT MONO (-1795 7287);
FORCEPROP 1 LASTPIN (-1800 7125) $PN 2
J 0
(-1795 7135);
DISPLAY 0.787234 (-1795 7135);
PAINT MONO (-1795 7135);
FORCEPROP 1 LAST PATH I78
J 0
(-1750 7400);
DISPLAY 0.978723 (-1750 7400);
PAINT WHITE (-1750 7400);
DISPLAY INVISIBLE (-1750 7400);
FORCEPROP 2 LAST CDS_LIB pure_quanta
J 0
(-1800 7225);
DISPLAY INVISIBLE (-1800 7225);
FORCEPROP 0 LAST $SEC 1
J 0
(-1750 7400);
DISPLAY 0.680851 (-1750 7400);
PAINT MONO (-1750 7400);
DISPLAY INVISIBLE (-1750 7400);
FORCEPROP 0 LAST CDS_SEC 1
J 0
(-1750 7400);
DISPLAY 1.021277 (-1750 7400);
DISPLAY INVISIBLE (-1750 7400);
FORCEADD Q_RES..2
(-1275 7225);
FORCEPROP 1 LAST PART_NUMBER CS12436F201
J 0
(-1235 7100);
DISPLAY 0.638298 (-1235 7100);
DISPLAY INVISIBLE (-1235 7100);
FORCEPROP 1 LAST TOLERANCE 1%
J 0
(-1230 7250);
DISPLAY 0.638298 (-1230 7250);
FORCEPROP 1 LAST VALUE 243
J 0
(-1230 7300);
DISPLAY 0.638298 (-1230 7300);
FORCEPROP 1 LAST WATTAGE 1/4W
J 0
(-1235 7200);
DISPLAY 0.638298 (-1235 7200);
FORCEPROP 1 LAST MATERIAL CHIP
J 0
(-1235 7150);
DISPLAY 0.638298 (-1235 7150);
FORCEPROP 1 LAST PACK_TYPE 1206LF
J 0
(-1235 7050);
DISPLAY 0.638298 (-1235 7050);
FORCEPROP 1 LAST LOCATION R4640
J 0
(-1230 7350);
DISPLAY 0.638298 (-1230 7350);
FORCEPROP 1 LASTPIN (-1275 7325) $PN 1
J 0
(-1270 7287);
DISPLAY 0.787234 (-1270 7287);
PAINT MONO (-1270 7287);
FORCEPROP 1 LASTPIN (-1275 7125) $PN 2
J 0
(-1270 7135);
DISPLAY 0.787234 (-1270 7135);
PAINT MONO (-1270 7135);
FORCEPROP 1 LAST PATH I79
J 0
(-1225 7400);
DISPLAY 0.978723 (-1225 7400);
PAINT WHITE (-1225 7400);
DISPLAY INVISIBLE (-1225 7400);
FORCEPROP 2 LAST CDS_LIB pure_quanta
J 0
(-1275 7225);
DISPLAY INVISIBLE (-1275 7225);
FORCEPROP 0 LAST $SEC 1
J 0
(-1225 7400);
DISPLAY 0.680851 (-1225 7400);
PAINT MONO (-1225 7400);
DISPLAY INVISIBLE (-1225 7400);
FORCEPROP 0 LAST CDS_SEC 1
J 0
(-1225 7400);
DISPLAY 1.021277 (-1225 7400);
DISPLAY INVISIBLE (-1225 7400);
FORCEADD OFFPAGE..1
(-7125 4925);
FORCEPROP 2 LAST $XR1 224 
J 0
(-7497 4925);
DISPLAY 0.638298 (-7497 4925);
PAINT MONO (-7497 4925);
FORCEPROP 2 LAST $XR0 214 
J 0
(-7377 4925);
DISPLAY 0.638298 (-7377 4925);
PAINT MONO (-7377 4925);
FORCEPROP 2 LAST PATH I8
J 0
(-7375 4975);
DISPLAY 1.021277 (-7375 4975);
DISPLAY INVISIBLE (-7375 4975);
FORCEPROP 2 LAST CDS_LIB standard
J 0
(-7125 4925);
DISPLAY INVISIBLE (-7125 4925);
FORCEPROP 1 LAST OFFPAGE TRUE
J 0
(-6800 4800);
DISPLAY 1.042553 (-6800 4800);
PAINT GREEN (-6800 4800);
DISPLAY INVISIBLE (-6800 4800);
FORCEPROP 1 LAST COMMENT_BODY TRUE
J 0
(-7000 4825);
DISPLAY 1.042553 (-7000 4825);
PAINT GREEN (-7000 4825);
DISPLAY INVISIBLE (-7000 4825);
FORCEPROP 2 LAST BOM_COST VR_SYSTEM 
J 0
(-7400 4975);
DISPLAY 0.617021 (-7400 4975);
PAINT PURPLE (-7400 4975);
DISPLAY INVISIBLE (-7400 4975);
FORCEADD Q_RES..2
(-750 7225);
FORCEPROP 1 LAST PART_NUMBER CS12436F201
J 0
(-710 7100);
DISPLAY 0.638298 (-710 7100);
DISPLAY INVISIBLE (-710 7100);
FORCEPROP 1 LAST TOLERANCE 1%
J 0
(-705 7250);
DISPLAY 0.638298 (-705 7250);
FORCEPROP 1 LAST VALUE 243
J 0
(-705 7300);
DISPLAY 0.638298 (-705 7300);
FORCEPROP 1 LAST WATTAGE 1/4W
J 0
(-710 7200);
DISPLAY 0.638298 (-710 7200);
FORCEPROP 1 LAST MATERIAL CHIP
J 0
(-710 7150);
DISPLAY 0.638298 (-710 7150);
FORCEPROP 1 LAST PACK_TYPE 1206LF
J 0
(-710 7050);
DISPLAY 0.638298 (-710 7050);
FORCEPROP 1 LAST LOCATION R4641
J 0
(-705 7350);
DISPLAY 0.638298 (-705 7350);
FORCEPROP 1 LASTPIN (-750 7325) $PN 1
J 0
(-745 7287);
DISPLAY 0.787234 (-745 7287);
PAINT MONO (-745 7287);
FORCEPROP 1 LASTPIN (-750 7125) $PN 2
J 0
(-745 7135);
DISPLAY 0.787234 (-745 7135);
PAINT MONO (-745 7135);
FORCEPROP 1 LAST PATH I80
J 0
(-700 7400);
DISPLAY 0.978723 (-700 7400);
PAINT WHITE (-700 7400);
DISPLAY INVISIBLE (-700 7400);
FORCEPROP 2 LAST CDS_LIB pure_quanta
J 0
(-750 7225);
DISPLAY INVISIBLE (-750 7225);
FORCEPROP 0 LAST $SEC 1
J 0
(-700 7400);
DISPLAY 0.680851 (-700 7400);
PAINT MONO (-700 7400);
DISPLAY INVISIBLE (-700 7400);
FORCEPROP 0 LAST CDS_SEC 1
J 0
(-700 7400);
DISPLAY 1.021277 (-700 7400);
DISPLAY INVISIBLE (-700 7400);
FORCEADD UNIVERSAL_GND..1
(-6075 3200);
FORCEPROP 3 LASTPIN (-6075 3250) SIG_NAME GND\g
J 0
(-6065 3260);
DISPLAY 0.659574 (-6065 3260);
PAINT MONO (-6065 3260);
DISPLAY INVISIBLE (-6065 3260);
FORCEPROP 0 LAST VOLTAGE 0
J 0
(-6075 3200);
PAINT SKYBLUE (-6075 3200);
DISPLAY INVISIBLE (-6075 3200);
FORCEPROP 1 LAST HDL_POWER GND
J 1
(-6050 3125);
DISPLAY 0.872340 (-6050 3125);
PAINT GREEN (-6050 3125);
DISPLAY INVISIBLE (-6050 3125);
FORCEPROP 2 LAST BOM_COST VR_SYSTEM 
J 0
(-6375 3275);
DISPLAY 0.680851 (-6375 3275);
DISPLAY INVISIBLE (-6375 3275);
FORCEPROP 1 LAST PATH I87
J 0
(-6000 3200);
DISPLAY 0.872340 (-6000 3200);
PAINT AQUA (-6000 3200);
DISPLAY INVISIBLE (-6000 3200);
FORCEPROP 2 LAST CDS_LIB logical_power
J 0
(-6075 3200);
DISPLAY INVISIBLE (-6075 3200);
FORCEADD Q_RES..2
(-5900 3350);
FORCEPROP 1 LAST PART_NUMBER CS31002FB08
J 0
(-5860 3225);
DISPLAY 0.617021 (-5860 3225);
DISPLAY INVISIBLE (-5860 3225);
FORCEPROP 1 LAST TOLERANCE 1%
J 0
(-5855 3375);
DISPLAY 0.617021 (-5855 3375);
FORCEPROP 1 LAST WATTAGE 1/16W
J 0
(-5860 3325);
DISPLAY 0.617021 (-5860 3325);
FORCEPROP 1 LAST MATERIAL EMPTY
J 0
(-5860 3275);
DISPLAY 0.617021 (-5860 3275);
FORCEPROP 1 LAST VALUE 10K
J 0
(-5855 3425);
DISPLAY 0.617021 (-5855 3425);
FORCEPROP 1 LAST PACK_TYPE 0402LF
J 0
(-5860 3175);
DISPLAY 0.617021 (-5860 3175);
FORCEPROP 1 LAST $LOCATION R1706
J 0
(-5855 3475);
DISPLAY 0.978723 (-5855 3475);
FORCEPROP 1 LASTPIN (-5900 3450) $PN 1
J 0
(-5895 3412);
DISPLAY 0.787234 (-5895 3412);
PAINT MONO (-5895 3412);
FORCEPROP 1 LASTPIN (-5900 3250) $PN 2
J 0
(-5895 3260);
DISPLAY 0.787234 (-5895 3260);
PAINT MONO (-5895 3260);
FORCEPROP 2 LAST CDS_LIB pure_quanta
J 0
(-5900 3350);
DISPLAY INVISIBLE (-5900 3350);
FORCEPROP 1 LAST PATH I89
J 0
(-5850 3525);
DISPLAY 0.978723 (-5850 3525);
PAINT WHITE (-5850 3525);
DISPLAY INVISIBLE (-5850 3525);
FORCEPROP 0 LAST CDS_LOCATION R1706
J 0
(-5850 3525);
DISPLAY 1.021277 (-5850 3525);
DISPLAY INVISIBLE (-5850 3525);
FORCEPROP 0 LAST $SEC 1
J 0
(-5850 3525);
DISPLAY 0.680851 (-5850 3525);
PAINT MONO (-5850 3525);
DISPLAY INVISIBLE (-5850 3525);
FORCEPROP 0 LAST CDS_SEC 1
J 0
(-5850 3525);
DISPLAY 1.021277 (-5850 3525);
DISPLAY INVISIBLE (-5850 3525);
FORCEADD Q_RES..1
(-6275 4700);
FORCEPROP 1 LAST PART_NUMBER CS00002JB13
J 0
(-6425 4750);
DISPLAY 0.617021 (-6425 4750);
DISPLAY INVISIBLE (-6425 4750);
FORCEPROP 1 LAST PACK_TYPE 0402LF
J 0
(-6425 4800);
DISPLAY 0.617021 (-6425 4800);
FORCEPROP 1 LAST MATERIAL CHIP
J 0
(-6025 4700);
DISPLAY 0.617021 (-6025 4700);
FORCEPROP 1 LAST VALUE 0
J 2
(-6125 4700);
DISPLAY 0.617021 (-6125 4700);
FORCEPROP 1 LAST WATTAGE 1/16W
J 2
(-6075 4800);
DISPLAY 0.617021 (-6075 4800);
FORCEPROP 1 LAST TOLERANCE 5%
J 0
(-6100 4700);
DISPLAY 0.617021 (-6100 4700);
FORCEPROP 1 LAST $LOCATION R1640
J 0
(-6525 4700);
DISPLAY 0.638298 (-6525 4700);
FORCEPROP 1 LASTPIN (-6375 4700) $PN 1
J 0
(-6363 4712);
DISPLAY 0.787234 (-6363 4712);
FORCEPROP 1 LASTPIN (-6175 4700) $PN 2
J 0
(-6213 4712);
DISPLAY 0.787234 (-6213 4712);
FORCEPROP 1 LAST PATH I9
J 0
(-6325 4850);
DISPLAY 0.978723 (-6325 4850);
PAINT WHITE (-6325 4850);
DISPLAY INVISIBLE (-6325 4850);
FORCEPROP 2 LAST BOM_COST VR_SYSTEM 
J 0
(-6325 4850);
DISPLAY 0.680851 (-6325 4850);
DISPLAY INVISIBLE (-6325 4850);
FORCEPROP 2 LAST CDS_LIB pure_quanta
J 0
(-6275 4700);
PAINT MONO (-6275 4700);
DISPLAY INVISIBLE (-6275 4700);
FORCEPROP 2 LAST CDS_LOCATION R1640
J 0
(-6325 4900);
DISPLAY 1.021277 (-6325 4900);
DISPLAY INVISIBLE (-6325 4900);
FORCEPROP 2 LAST $SEC 1
J 0
(-6325 4900);
DISPLAY 0.680851 (-6325 4900);
PAINT MONO (-6325 4900);
DISPLAY INVISIBLE (-6325 4900);
FORCEPROP 2 LAST CDS_SEC 1
J 0
(-6325 4900);
DISPLAY 1.021277 (-6325 4900);
DISPLAY INVISIBLE (-6325 4900);
FORCEADD Q_RES..1
(-5325 3100);
FORCEPROP 1 LAST PART_NUMBER CS03322FB03
J 0
(-5725 3000);
DISPLAY 0.723404 (-5725 3000);
PAINT WHITE (-5725 3000);
DISPLAY INVISIBLE (-5725 3000);
FORCEPROP 1 LAST MATERIAL CHIP
J 0
(-5300 3050);
DISPLAY 0.723404 (-5300 3050);
FORCEPROP 1 LAST VALUE 33.2
J 2
(-5075 3100);
DISPLAY 0.723404 (-5075 3100);
FORCEPROP 1 LAST PACK_TYPE 0402LF
J 0
(-5500 3050);
DISPLAY 0.723404 (-5500 3050);
FORCEPROP 1 LAST $LOCATION R4677
J 0
(-5375 3150);
DISPLAY 0.978723 (-5375 3150);
FORCEPROP 1 LASTPIN (-5425 3100) $PN 1
J 0
(-5413 3112);
DISPLAY 0.787234 (-5413 3112);
PAINT MONO (-5413 3112);
FORCEPROP 1 LASTPIN (-5225 3100) $PN 2
J 0
(-5263 3112);
DISPLAY 0.787234 (-5263 3112);
PAINT MONO (-5263 3112);
FORCEPROP 2 LAST CDS_LIB pure_quanta
J 0
(-5325 3100);
DISPLAY INVISIBLE (-5325 3100);
FORCEPROP 1 LAST PATH I91
J 0
(-5375 3250);
DISPLAY 0.978723 (-5375 3250);
PAINT WHITE (-5375 3250);
DISPLAY INVISIBLE (-5375 3250);
FORCEPROP 1 LAST WATTAGE 1/16W
J 2
(-4925 3050);
DISPLAY 0.723404 (-4925 3050);
PAINT SKYBLUE (-4925 3050);
DISPLAY INVISIBLE (-4925 3050);
FORCEPROP 1 LAST TOLERANCE 1%
J 0
(-4850 3100);
DISPLAY 0.723404 (-4850 3100);
PAINT SKYBLUE (-4850 3100);
DISPLAY INVISIBLE (-4850 3100);
FORCEPROP 0 LAST CDS_LOCATION R4677
J 0
(-5375 3200);
DISPLAY 1.021277 (-5375 3200);
DISPLAY INVISIBLE (-5375 3200);
FORCEPROP 0 LAST $SEC 1
J 0
(-5375 3200);
DISPLAY 0.680851 (-5375 3200);
PAINT MONO (-5375 3200);
DISPLAY INVISIBLE (-5375 3200);
FORCEPROP 0 LAST CDS_SEC 1
J 0
(-5375 3200);
DISPLAY 1.021277 (-5375 3200);
DISPLAY INVISIBLE (-5375 3200);
FORCEADD OFFPAGE..2
(-4650 3100);
FORCEPROP 2 LAST $XR0 213 
J 0
(-4461 3100);
DISPLAY 0.638298 (-4461 3100);
PAINT MONO (-4461 3100);
FORCEPROP 2 LAST PATH I92
J 0
(-4450 3150);
DISPLAY 1.021277 (-4450 3150);
DISPLAY INVISIBLE (-4450 3150);
FORCEPROP 2 LAST BOM_COST VR_SYSTEM 
J 0
(-4900 3150);
DISPLAY 0.829787 (-4900 3150);
PAINT PURPLE (-4900 3150);
DISPLAY INVISIBLE (-4900 3150);
FORCEPROP 1 LAST COMMENT_BODY TRUE
J 0
(-4695 3005);
DISPLAY 0.872340 (-4695 3005);
PAINT GREEN (-4695 3005);
DISPLAY INVISIBLE (-4695 3005);
FORCEPROP 1 LAST OFFPAGE TRUE
J 0
(-4325 2975);
DISPLAY 0.872340 (-4325 2975);
PAINT GREEN (-4325 2975);
DISPLAY INVISIBLE (-4325 2975);
FORCEPROP 2 LAST CDS_LIB standard
J 1
(-4650 3100);
DISPLAY INVISIBLE (-4650 3100);
FORCEADD UNIVERSAL_POWER..1
(-1200 5075);
FORCEPROP 3 LASTPIN (-1200 5025) SIG_NAME P12V_AUX\g
J 0
(-1190 5035);
DISPLAY 0.659574 (-1190 5035);
PAINT MONO (-1190 5035);
DISPLAY INVISIBLE (-1190 5035);
FORCEPROP 1 LAST HDL_POWER P12V_AUX
J 1
(-1200 5125);
DISPLAY 0.617021 (-1200 5125);
PAINT GREEN (-1200 5125);
FORCEPROP 2 LAST CDS_LIB logical_power
J 0
(-1200 5075);
DISPLAY INVISIBLE (-1200 5075);
FORCEPROP 1 LAST PATH I93
J 0
(-1150 5100);
DISPLAY 0.872340 (-1150 5100);
PAINT AQUA (-1150 5100);
DISPLAY INVISIBLE (-1150 5100);
FORCEPROP 2 LAST BOM_COST VR_SYSTEM 
J 0
(-1200 5175);
DISPLAY 0.680851 (-1200 5175);
DISPLAY INVISIBLE (-1200 5175);
FORCEADD Q_CAP..1
(175 4075);
FORCEPROP 1 LAST PART_NUMBER CH4224K1B01
J 0
(225 3925);
DISPLAY 0.617021 (225 3925);
DISPLAY INVISIBLE (225 3925);
FORCEPROP 1 LAST VALUE 0.22UF
J 0
(225 4125);
DISPLAY 0.617021 (225 4125);
FORCEPROP 1 LAST VOLTAGE 25V
J 0
(225 4075);
DISPLAY 0.617021 (225 4075);
FORCEPROP 1 LAST TOLERANCE 10%
J 0
(225 4025);
DISPLAY 0.617021 (225 4025);
FORCEPROP 1 LAST MATERIAL X7R
J 0
(225 3975);
DISPLAY 0.617021 (225 3975);
FORCEPROP 1 LAST PACK_TYPE C0402
J 0
(225 3875);
DISPLAY 0.617021 (225 3875);
FORCEPROP 1 LAST $LOCATION C2359
J 0
(225 4175);
DISPLAY 0.617021 (225 4175);
FORCEPROP 1 LASTPIN (175 4175) $PN 1
J 0
(185 4155);
DISPLAY 0.787234 (185 4155);
PAINT MONO (185 4155);
FORCEPROP 1 LASTPIN (175 3975) $PN 2
J 0
(185 3955);
DISPLAY 0.787234 (185 3955);
PAINT MONO (185 3955);
FORCEPROP 1 LAST PATH I94
J 0
(225 4225);
DISPLAY 0.978723 (225 4225);
PAINT WHITE (225 4225);
DISPLAY INVISIBLE (225 4225);
FORCEPROP 2 LAST CDS_LIB pure_quanta
J 0
(175 4075);
DISPLAY INVISIBLE (175 4075);
FORCEPROP 0 LAST CDS_LOCATION C2359
J 0
(225 4225);
DISPLAY 1.021277 (225 4225);
DISPLAY INVISIBLE (225 4225);
FORCEPROP 0 LAST $SEC 1
J 0
(225 4225);
DISPLAY 0.680851 (225 4225);
PAINT MONO (225 4225);
DISPLAY INVISIBLE (225 4225);
FORCEPROP 0 LAST CDS_SEC 1
J 0
(225 4225);
DISPLAY 1.021277 (225 4225);
DISPLAY INVISIBLE (225 4225);
FORCEADD UNIVERSAL_GND..1
(175 3800);
FORCEPROP 3 LASTPIN (175 3850) SIG_NAME GND\g
J 0
(185 3860);
DISPLAY 0.659574 (185 3860);
PAINT MONO (185 3860);
DISPLAY INVISIBLE (185 3860);
FORCEPROP 0 LAST VOLTAGE 0
J 0
(175 3800);
PAINT SKYBLUE (175 3800);
DISPLAY INVISIBLE (175 3800);
FORCEPROP 1 LAST HDL_POWER GND
J 1
(200 3725);
DISPLAY 0.872340 (200 3725);
PAINT GREEN (200 3725);
DISPLAY INVISIBLE (200 3725);
FORCEPROP 2 LAST BOM_COST VR_SYSTEM 
J 0
(-125 3875);
DISPLAY 0.680851 (-125 3875);
DISPLAY INVISIBLE (-125 3875);
FORCEPROP 1 LAST PATH I95
J 0
(250 3800);
DISPLAY 0.872340 (250 3800);
PAINT AQUA (250 3800);
DISPLAY INVISIBLE (250 3800);
FORCEPROP 2 LAST CDS_LIB logical_power
J 0
(175 3800);
DISPLAY INVISIBLE (175 3800);
FORCEADD Q_RES..2
(-2700 3975);
FORCEPROP 1 LAST PART_NUMBER CS31002FB08
J 0
(-2660 3850);
DISPLAY 0.617021 (-2660 3850);
DISPLAY INVISIBLE (-2660 3850);
FORCEPROP 1 LAST PACK_TYPE 0402LF
J 0
(-2660 3800);
DISPLAY 0.617021 (-2660 3800);
FORCEPROP 1 LAST VALUE 10K
J 0
(-2655 4050);
DISPLAY 0.617021 (-2655 4050);
FORCEPROP 1 LAST TOLERANCE 1%
J 0
(-2655 4000);
DISPLAY 0.617021 (-2655 4000);
FORCEPROP 1 LAST WATTAGE 1/16W
J 0
(-2660 3950);
DISPLAY 0.617021 (-2660 3950);
FORCEPROP 1 LAST MATERIAL CHIP
J 0
(-2660 3900);
DISPLAY 0.617021 (-2660 3900);
FORCEPROP 1 LAST $LOCATION R4679
J 0
(-2655 4100);
DISPLAY 0.978723 (-2655 4100);
FORCEPROP 1 LASTPIN (-2700 4075) $PN 1
J 0
(-2695 4037);
DISPLAY 0.787234 (-2695 4037);
PAINT MONO (-2695 4037);
FORCEPROP 1 LASTPIN (-2700 3875) $PN 2
J 0
(-2695 3885);
DISPLAY 0.787234 (-2695 3885);
PAINT MONO (-2695 3885);
FORCEPROP 1 LAST PATH I96
J 0
(-2650 4150);
DISPLAY 0.978723 (-2650 4150);
PAINT WHITE (-2650 4150);
DISPLAY INVISIBLE (-2650 4150);
FORCEPROP 2 LAST CDS_LIB pure_quanta
J 0
(-2700 3975);
DISPLAY INVISIBLE (-2700 3975);
FORCEPROP 0 LAST CDS_LOCATION R4679
J 0
(-2650 4150);
DISPLAY 1.021277 (-2650 4150);
DISPLAY INVISIBLE (-2650 4150);
FORCEPROP 0 LAST $SEC 1
J 0
(-2650 4150);
DISPLAY 0.680851 (-2650 4150);
PAINT MONO (-2650 4150);
DISPLAY INVISIBLE (-2650 4150);
FORCEPROP 0 LAST CDS_SEC 1
J 0
(-2650 4150);
DISPLAY 1.021277 (-2650 4150);
DISPLAY INVISIBLE (-2650 4150);
FORCEADD MOSFET_NCH_DUAL..2
(-1250 3750);
FORCEPROP 1 LAST PART_NUMBER BAM138K0003
J 0
(-1099 3656);
DISPLAY 0.723404 (-1099 3656);
PAINT GREEN (-1099 3656);
DISPLAY INVISIBLE (-1099 3656);
FORCEPROP 1 LAST MATERIAL IC
J 0
(-1099 3601);
DISPLAY 0.723404 (-1099 3601);
PAINT GREEN (-1099 3601);
FORCEPROP 2 LAST PART_TYPE SMLF
J 0
(-1075 3825);
DISPLAY 1.021277 (-1075 3825);
FORCEPROP 2 LAST VALUE PJT138K
J 0
(-1075 3775);
DISPLAY 1.021277 (-1075 3775);
FORCEPROP 1 LAST LOCATION Q236
J 0
(-1099 3726);
DISPLAY 0.723404 (-1099 3726);
PAINT GREEN (-1099 3726);
FORCEPROP 0 LASTPIN (-1200 3950) $PN 3
R 1
J 0
(-1210 3960);
DISPLAY 0.680851 (-1210 3960);
PAINT MONO (-1210 3960);
FORCEPROP 0 LASTPIN (-1450 3700) $PN 5
J 2
(-1460 3710);
DISPLAY 0.680851 (-1460 3710);
PAINT MONO (-1460 3710);
FORCEPROP 0 LASTPIN (-1200 3550) $PN 4
R 1
J 2
(-1210 3540);
DISPLAY 0.680851 (-1210 3540);
PAINT MONO (-1210 3540);
FORCEPROP 2 LAST CDS_LIB pure_quanta
J 0
(-1250 3750);
DISPLAY INVISIBLE (-1250 3750);
FORCEPROP 1 LAST PATH I98
J 0
(-1100 3600);
DISPLAY 0.723404 (-1100 3600);
PAINT GREEN (-1100 3600);
DISPLAY INVISIBLE (-1100 3600);
FORCEPROP 1 LAST CDS_LMAN_SYM_OUTLINE -150,150,150,-150
J 0
(-1250 3750);
DISPLAY 0.468085 (-1250 3750);
PAINT GREEN (-1250 3750);
DISPLAY INVISIBLE (-1250 3750);
FORCEPROP 1 LAST NEEDS_NO_SIZE TRUE
J 0
(-1100 3641);
DISPLAY 0.468085 (-1100 3641);
PAINT GREEN (-1100 3641);
DISPLAY INVISIBLE (-1100 3641);
FORCEPROP 0 LAST $SEC 2
J 0
(-1075 3875);
DISPLAY 0.680851 (-1075 3875);
PAINT MONO (-1075 3875);
DISPLAY INVISIBLE (-1075 3875);
FORCEPROP 0 LAST CDS_SEC 2
J 0
(-1075 3875);
DISPLAY 1.021277 (-1075 3875);
DISPLAY INVISIBLE (-1075 3875);
FORCEADD MOSFET_NCH_DUAL..1
(-2075 3775);
FORCEPROP 1 LAST PART_NUMBER BAM138K0003
J 0
(-1924 3689);
DISPLAY 0.723404 (-1924 3689);
PAINT GREEN (-1924 3689);
DISPLAY INVISIBLE (-1924 3689);
FORCEPROP 1 LAST MATERIAL IC
J 0
(-1924 3624);
DISPLAY 0.723404 (-1924 3624);
PAINT GREEN (-1924 3624);
FORCEPROP 2 LAST VALUE PJT138K
J 0
(-1900 3800);
DISPLAY 1.021277 (-1900 3800);
FORCEPROP 2 LAST PART_TYPE SMLF
J 0
(-1900 3850);
DISPLAY 1.021277 (-1900 3850);
FORCEPROP 1 LAST LOCATION Q236
J 0
(-1924 3749);
DISPLAY 0.723404 (-1924 3749);
PAINT GREEN (-1924 3749);
FORCEPROP 0 LASTPIN (-2025 3975) $PN 6
R 1
J 0
(-2035 3985);
DISPLAY 0.680851 (-2035 3985);
PAINT MONO (-2035 3985);
FORCEPROP 0 LASTPIN (-2275 3725) $PN 2
J 2
(-2285 3735);
DISPLAY 0.680851 (-2285 3735);
PAINT MONO (-2285 3735);
FORCEPROP 0 LASTPIN (-2025 3575) $PN 1
R 1
J 2
(-2035 3565);
DISPLAY 0.680851 (-2035 3565);
PAINT MONO (-2035 3565);
FORCEPROP 1 LAST NEEDS_NO_SIZE TRUE
J 0
(-2075 3774);
DISPLAY 0.468085 (-2075 3774);
PAINT GREEN (-2075 3774);
DISPLAY INVISIBLE (-2075 3774);
FORCEPROP 1 LAST CDS_LMAN_SYM_OUTLINE -150,150,150,-150
J 0
(-2075 3775);
DISPLAY 0.468085 (-2075 3775);
PAINT GREEN (-2075 3775);
DISPLAY INVISIBLE (-2075 3775);
FORCEPROP 1 LAST PATH I99
J 0
(-2075 3775);
DISPLAY 0.723404 (-2075 3775);
PAINT GREEN (-2075 3775);
DISPLAY INVISIBLE (-2075 3775);
FORCEPROP 2 LAST CDS_LIB pure_quanta
J 0
(-2075 3775);
DISPLAY INVISIBLE (-2075 3775);
FORCEPROP 0 LAST $SEC 1
J 0
(-1900 3900);
DISPLAY 0.680851 (-1900 3900);
PAINT MONO (-1900 3900);
DISPLAY INVISIBLE (-1900 3900);
FORCEPROP 0 LAST CDS_SEC 1
J 0
(-1900 3900);
DISPLAY 1.021277 (-1900 3900);
DISPLAY INVISIBLE (-1900 3900);
FORCEADD DNS..1
(-425 5525);
PAINT RED (-425 5525);
FORCEPROP 2 LAST CDS_LIB mstr_misc
J 0
(-425 5525);
DISPLAY INVISIBLE (-425 5525);
FORCEPROP 1 LAST COMMENT_BODY TRUE
J 0
(-425 5525);
DISPLAY INVISIBLE (-425 5525);
FORCEPROP 2 LAST BOM_COST VR_SYSTEM 
J 0
(-600 5700);
DISPLAY 0.680851 (-600 5700);
DISPLAY INVISIBLE (-600 5700);
FORCEADD DNS..1
(-5320 7520);
PAINT RED (-5320 7520);
FORCEPROP 2 LAST CDS_LIB mstr_misc
J 0
(-5320 7520);
DISPLAY INVISIBLE (-5320 7520);
FORCEPROP 1 LAST COMMENT_BODY TRUE
J 0
(-5320 7520);
DISPLAY INVISIBLE (-5320 7520);
FORCEPROP 2 LAST BOM_COST VR_SYSTEM 
J 0
(-5500 7700);
DISPLAY 0.680851 (-5500 7700);
DISPLAY INVISIBLE (-5500 7700);
FORCEADD DNS..1
(-6275 4950);
PAINT RED (-6275 4950);
FORCEPROP 2 LAST BOM_COST VR_SYSTEM 
J 0
(-6450 5125);
DISPLAY 0.680851 (-6450 5125);
DISPLAY INVISIBLE (-6450 5125);
FORCEPROP 1 LAST COMMENT_BODY TRUE
J 0
(-6275 4950);
DISPLAY INVISIBLE (-6275 4950);
FORCEPROP 2 LAST CDS_LIB mstr_misc
J 0
(-6275 4950);
PAINT MONO (-6275 4950);
DISPLAY INVISIBLE (-6275 4950);
FORCEADD DNS..1
(-5900 3325);
PAINT RED (-5900 3325);
FORCEPROP 2 LAST CDS_LIB mstr_misc
J 0
(-5900 3325);
DISPLAY INVISIBLE (-5900 3325);
FORCEPROP 1 LAST COMMENT_BODY TRUE
J 0
(-5900 3325);
DISPLAY INVISIBLE (-5900 3325);
FORCEPROP 2 LAST BOM_COST VR_SYSTEM 
J 0
(-6075 3500);
DISPLAY 0.680851 (-6075 3500);
DISPLAY INVISIBLE (-6075 3500);
FORCEADD QUANTA_TITLE_BLOCK_C..1
(1500 1650);
FORCEPROP 0 LAST CDS_CON_LAST_MODIFIED Fri Aug 25 14:04:32 2023
J 0
(-385 1665);
DISPLAY INVISIBLE (-385 1665);
FORCEPROP 2 LAST CUSTOM_TXT_CDS <XR_PAGE_TITLE>
J 0
(-6390 6900);
DISPLAY 0.638298 (-6390 6900);
PAINT PINK (-6390 6900);
DISPLAY INVISIBLE (-6390 6900);
FORCEPROP 2 LAST CUSTOM_TXT_CDS <CON_LAST_MODIFIED>
J 0
(-385 1665);
DISPLAY 0.978723 (-385 1665);
FORCEPROP 2 LAST CUSTOM_TXT_CDS <NAME_1>
J 0
(-1675 1825);
FORCEPROP 2 LAST CUSTOM_TXT_CDS <Q_NUMBER>
J 0
(97 1753);
DISPLAY 1.212766 (97 1753);
FORCEPROP 2 LAST CUSTOM_TXT_CDS <Q_PROJ>
J 0
(-882 1752);
DISPLAY 1.212766 (-882 1752);
FORCEPROP 2 LAST CUSTOM_TXT_CDS <Q_REV>
J 0
(1316 1753);
DISPLAY 1.212766 (1316 1753);
FORCEPROP 2 LAST CUSTOM_TXT_CDS <CON_PAGE_NUM> OF <CON_TOTAL_PAGES>
J 0
(1054 1668);
DISPLAY 0.978723 (1054 1668);
FORCEPROP 2 LAST CUSTOM_TXT_CDS <NAME_2>
J 0
(-1675 1700);
FORCEPROP 1 LAST Q_TITLE P5V & P3V3 SWITCH
J 0
(-7866 1676);
DISPLAY 2.446809 (-7866 1676);
PAINT GREEN (-7866 1676);
FORCEPROP 1 LAST Q_DEPT 
J 1
(-2263 1699);
DISPLAY 1.957447 (-2263 1699);
PAINT GREEN (-2263 1699);
FORCEPROP 2 LAST CDS_XR_PAGE_TITLE CR-260 : @S9S_MB_2U_LIB.S9S_MB_2U(SCH_1):PAGE260
J 0
(-6390 6900);
DISPLAY 0.638298 (-6390 6900);
PAINT PINK (-6390 6900);
DISPLAY INVISIBLE (-6390 6900);
FORCEPROP 2 LAST CDS_LIB pure_quanta
J 0
(1500 1650);
DISPLAY INVISIBLE (1500 1650);
FORCEPROP 1 LAST CDS_LMAN_SYM_OUTLINE -9475,6775,100,-125
J 0
(1500 1650);
DISPLAY 0.468085 (1500 1650);
PAINT GREEN (1500 1650);
DISPLAY INVISIBLE (1500 1650);
FORCEPROP 2 LAST PAGE_BORDER TRUE
J 0
(-6390 6900);
DISPLAY 0.638298 (-6390 6900);
PAINT PINK (-6390 6900);
DISPLAY INVISIBLE (-6390 6900);
FORCEPROP 1 LAST COMMENT_BODY TRUE
J 0
(1512 1637);
DISPLAY 0.978723 (1512 1637);
PAINT GREEN (1512 1637);
DISPLAY INVISIBLE (1512 1637);
FORCEPROP 2 LAST BOM_COST VR_SYSTEM 
J 0
(-1675 1850);
DISPLAY 0.680851 (-1675 1850);
DISPLAY INVISIBLE (-1675 1850);
WIRE 16 -1 (-2025 4375)(-2025 4500);
WIRE 16 -1 (-5900 3625)(-5900 3450);
WIRE 16 -1 (-4075 3900)(-4075 3625);
WIRE 16 -1 (-2700 4250)(-2700 4075);
WIRE 16 -1 (-7200 3200)(-7200 3400);
WIRE 16 -1 (-7200 3100)(-7200 3200);
WIRE 16 -1 (-7200 3200)(-7025 3200);
WIRE 16 -1 (-1200 5025)(-1200 4900);
WIRE 16 -1 (-251 5899)(-251 5725);
WIRE 16 -1 (675 5300)(675 5475);
WIRE 16 -1 (675 4725)(675 5300);
WIRE 16 -1 (775 5300)(675 5300);
WIRE 16 -1 (-5125 5625)(-5125 5750);
WIRE 16 -1 (-3475 7575)(-3475 7825);
WIRE 16 -1 (-3375 7575)(-3475 7575);
WIRE 16 -1 (-3475 6975)(-3475 7575);
WIRE 16 -1 (-5151 7799)(-5151 7725);
WIRE 16 -1 (-5975 6600)(-5975 6850);
WIRE 16 -1 (-5675 6600)(-5975 6600);
WIRE 16 -1 (-6625 1975)(-6625 2200);
WIRE 16 -1 (-6625 1975)(-6300 1975);
WIRE 16 -1 (-5650 1975)(-5650 2200);
WIRE 16 -1 (-6050 1975)(-5650 1975);
WIRE 16 -1 (-6075 3300)(-6075 3250);
WIRE 16 -1 (-6075 3300)(-6275 3300);
WIRE 16 -1 (-1200 3550)(-1200 3350);
WIRE 16 -1 (-1150 5325)(-1150 5275);
WIRE 16 -1 (-825 5325)(-1150 5325);
WIRE 16 -1 (-1150 5450)(-1150 5325);
WIRE 16 -1 (-2800 3525)(-2800 3400);
WIRE 16 -1 (-3025 3525)(-2800 3525);
WIRE 16 -1 (-2025 3575)(-2025 3350);
WIRE 16 -1 (1150 4900)(1150 4825);
WIRE 16 -1 (1150 4900)(775 4900);
WIRE 16 -1 (1150 5025)(1150 4900);
WIRE 16 -1 (-4075 3275)(-4075 3175);
WIRE 16 -1 (-5125 4775)(-5125 4550);
WIRE 16 -1 (-2350 6400)(-2350 6275);
WIRE 16 -1 (-3375 7175)(-3375 7125);
WIRE 16 -1 (-3050 7175)(-3375 7175);
WIRE 16 -1 (-3375 7300)(-3375 7175);
WIRE 16 -1 (-4350 5100)(-4350 4800);
WIRE 16 -1 (-5975 7325)(-5975 7250);
WIRE 16 -1 (-5975 7325)(-5650 7325);
WIRE 16 -1 (-5975 7450)(-5975 7325);
WIRE 16 -1 (-3950 6200)(-3950 6075);
WIRE 16 -1 (175 3975)(175 3850);
WIRE 16 -1 (-7200 2900)(-7200 2825);
WIRE 16 -1 (-5775 4550)(-5775 4325);
WIRE 16 -1 (-5875 2800)(-5875 2575);
WIRE 16 -1 (-2625 3425)(-2625 3200);
WIRE 16 2175 (-7550 3825)(-4322 3825);
WIRE 16 2175 (-4322 3825)(-4322 2450);
WIRE 16 2175 (-7550 3825)(-7550 2450);
WIRE 16 2175 (-7550 2450)(-4322 2450);
WIRE 16 2175 (-4250 5175)(-322 5175);
WIRE 16 2175 (-322 5175)(-322 2925);
WIRE 16 2175 (-4250 5175)(-4250 2925);
WIRE 16 2175 (-4250 2925)(-322 2925);
WIRE 16 -1 (-5875 4700)(-6175 4700);
WIRE 16 -1 (-5875 4925)(-6175 4925);
WIRE 16 -1 (-5875 4925)(-5875 4700);
WIRE 16 -1 (-5775 4750)(-5775 4925);
WIRE 16 -1 (-5775 4925)(-5875 4925);
WIRE 16 -1 (-5375 4925)(-5775 4925);
FORCEPROP 2 LAST SIG_NAME VR_P5V_EN
J 0
(-5735 4935);
DISPLAY 0.617021 (-5735 4935);
PAINT WHITE (-5735 4935);
WIRE 16 -1 (-7075 4925)(-6375 4925);
FORCEPROP 2 LAST SIG_NAME FM_PS_EN_PLD_R
J 0
(-7010 4935);
DISPLAY 0.617021 (-7010 4935);
PAINT WHITE (-7010 4935);
WIRE 16 -1 (-6275 3100)(-5900 3100);
WIRE 16 -1 (-5900 3250)(-5900 3100);
WIRE 16 -1 (-5875 3100)(-5875 3000);
WIRE 16 -1 (-5900 3100)(-5875 3100);
FORCEPROP 2 LAST SIG_NAME PWRGD_P3V3_R1
J 0
(-5885 3110);
DISPLAY 0.510638 (-5885 3110);
WIRE 16 -1 (-5875 3100)(-5425 3100);
WIRE 16 -1 (-1200 4575)(-1200 4500);
WIRE 16 -1 (-1200 4700)(-1200 4575);
WIRE 16 -1 (-650 4575)(-1200 4575);
WIRE 16 -1 (-650 4325)(-650 4575);
WIRE 16 -1 (175 4175)(175 4325);
WIRE 16 -1 (175 4325)(175 4425);
WIRE 16 -1 (175 4325)(-650 4325);
FORCEPROP 2 LAST SIG_NAME PWRGD_P5V_ISO_R
J 0
(-560 4335);
DISPLAY 0.617021 (-560 4335);
PAINT WHITE (-560 4335);
WIRE 16 -1 (-2025 3975)(-2025 4025);
WIRE 16 -1 (-2025 4025)(-2025 4175);
WIRE 16 -1 (-2025 4025)(-1550 4025);
FORCEPROP 2 LAST SIG_NAME PWRGD_P5V_N
J 0
(-1960 4035);
DISPLAY 0.617021 (-1960 4035);
PAINT WHITE (-1960 4035);
WIRE 16 -1 (-1550 4025)(-1550 3700);
WIRE 16 -1 (-1550 3700)(-1450 3700);
WIRE 16 -1 (-2625 3725)(-2625 3625);
WIRE 16 -1 (-2625 3725)(-2275 3725);
WIRE 16 -1 (-2700 3725)(-2625 3725);
FORCEPROP 2 LAST SIG_NAME PWRGD_P5V
J 0
(-2660 3735);
DISPLAY 0.765957 (-2660 3735);
PAINT WHITE (-2660 3735);
WIRE 16 -1 (-2700 3875)(-2700 3725);
WIRE 16 -1 (-3025 3725)(-2700 3725);
WIRE 16 -1 (-1200 4300)(-1200 3950);
FORCEPROP 2 LAST SIG_NAME PWRGD_P5V_ISO
R 1
J 0
(-1210 3960);
DISPLAY 0.510638 (-1210 3960);
PAINT WHITE (-1210 3960);
WIRE 16 -1 (-4700 3100)(-5225 3100);
FORCEPROP 2 LAST SIG_NAME PWRGD_P3V3
J 0
(-5010 3110);
DISPLAY 0.617021 (-5010 3110);
WIRE 16 -1 (-251 4625)(-125 4625);
WIRE 16 -1 (-251 5725)(-251 4625);
WIRE 16 -1 (-425 5650)(-425 5725);
WIRE 16 -1 (-425 5725)(-251 5725);
WIRE 16 -1 (-825 5650)(-825 5725);
WIRE 16 -1 (-425 5725)(-825 5725);
WIRE 16 -1 (-1150 5725)(-825 5725);
WIRE 16 -1 (-1150 5650)(-1150 5725);
WIRE 16 -1 (-4075 3475)(-4075 3625);
WIRE 16 -1 (-4075 3625)(-3775 3625);
WIRE 16 -1 (-5650 7450)(-5650 7325);
WIRE 16 -1 (-5325 7325)(-5650 7325);
WIRE 16 -1 (-5325 7450)(-5325 7325);
WIRE 16 -1 (-5151 6875)(-4250 6875);
WIRE 16 -1 (-5151 7725)(-5151 6875);
WIRE 16 -1 (-5325 7650)(-5325 7725);
WIRE 16 -1 (-5325 7725)(-5151 7725);
WIRE 16 -1 (-5650 7650)(-5650 7725);
WIRE 16 -1 (-5325 7725)(-5650 7725);
WIRE 16 -1 (-5975 7725)(-5650 7725);
WIRE 16 -1 (-5975 7650)(-5975 7725);
WIRE 16 -1 (-3475 6775)(-3750 6775);
WIRE 16 -1 (-3475 6875)(-3750 6875);
WIRE 16 -1 (-3475 6875)(-3475 6775);
WIRE 16 -1 (-3750 6975)(-3475 6975);
WIRE 16 -1 (-3475 6975)(-3475 6875);
WIRE 16 -1 (-3375 7500)(-3375 7575);
WIRE 16 -1 (-3375 7575)(-3050 7575);
WIRE 16 -1 (-3050 7500)(-3050 7575);
WIRE 16 -1 (-3050 7575)(-2350 7575);
WIRE 16 -1 (-2350 7425)(-2350 7325);
WIRE 16 -1 (-2350 7575)(-2350 7425);
WIRE 16 -1 (-2350 7425)(-1800 7425);
WIRE 16 -1 (-1800 7325)(-1800 7425);
WIRE 16 -1 (-1275 7425)(-1800 7425);
WIRE 16 -1 (-1275 7325)(-1275 7425);
WIRE 16 -1 (-750 7425)(-1275 7425);
WIRE 16 -1 (-750 7425)(-750 7325);
WIRE 16 -1 (-3050 7300)(-3050 7175);
WIRE 16 -1 (-825 5450)(-825 5325);
WIRE 16 -1 (-425 5325)(-825 5325);
WIRE 16 -1 (-425 5450)(-425 5325);
WIRE 16 -1 (1150 5225)(1150 5300);
WIRE 16 -1 (775 5225)(775 5300);
WIRE 16 -1 (775 5300)(1150 5300);
WIRE 16 -1 (375 4725)(675 4725);
WIRE 16 -1 (675 4625)(375 4625);
WIRE 16 -1 (675 4725)(675 4625);
WIRE 16 -1 (675 4525)(375 4525);
WIRE 16 -1 (675 4525)(675 4625);
WIRE 16 -1 (775 5025)(775 4900);
WIRE 16 -1 (-5125 5175)(-5125 5250);
WIRE 16 -1 (-5125 5425)(-5125 5250);
WIRE 16 -1 (-5125 5250)(-5050 5250);
FORCEPROP 2 LAST SIG_NAME VR_P5V_EN_N
J 0
(-5035 5260);
DISPLAY 0.617021 (-5035 5260);
PAINT WHITE (-5035 5260);
WIRE 16 -1 (-5050 5250)(-4600 5250);
WIRE 16 -1 (-5050 5250)(-5050 5125);
WIRE 16 -1 (-5050 5125)(-4850 5125);
WIRE 16 -1 (-7075 4700)(-6375 4700);
FORCEPROP 2 LAST SIG_NAME FM_P5V_EN
J 0
(-7010 4710);
DISPLAY 0.617021 (-7010 4710);
PAINT WHITE (-7010 4710);
WIRE 16 -1 (-4350 6200)(-4350 5500);
FORCEPROP 2 LAST SIG_NAME VR_P5V_EN_D_R1
R 1
J 0
(-4360 5585);
DISPLAY 0.617021 (-4360 5585);
PAINT WHITE (-4360 5585);
WIRE 16 -1 (-2350 7000)(-2350 6800);
FORCEPROP 2 LAST SIG_NAME VR_P5V_EN_D
R 1
J 0
(-2360 6860);
DISPLAY 0.638298 (-2360 6860);
PAINT WHITE (-2360 6860);
WIRE 16 -1 (-2350 7125)(-2350 7000);
WIRE 16 -1 (-2350 7000)(-1800 7000);
WIRE 16 -1 (-1800 7125)(-1800 7000);
WIRE 16 -1 (-1275 7000)(-1800 7000);
WIRE 16 -1 (-1275 7000)(-1275 7125);
WIRE 16 -1 (-750 7000)(-1275 7000);
WIRE 16 -1 (-750 7000)(-750 7125);
WIRE 16 2175 (-2600 6200)(-150 6200);
WIRE 16 2175 (-150 7500)(-150 6200);
WIRE 16 2175 (-2600 7500)(-2600 6200);
WIRE 16 2175 (-2600 7500)(-150 7500);
WIRE 16 -1 (-2550 6600)(-3075 6600);
FORCEPROP 2 LAST SIG_NAME VR_P5V_EN_N
J 0
(-2985 6610);
DISPLAY 0.617021 (-2985 6610);
PAINT WHITE (-2985 6610);
WIRE 16 -1 (-5475 6600)(-4350 6600);
FORCEPROP 2 LAST SIG_NAME VR_P5V_EN_D_R
J 0
(-4910 6600);
DISPLAY 0.617021 (-4910 6600);
PAINT WHITE (-4910 6600);
WIRE 16 -1 (-4350 6600)(-4350 6400);
WIRE 16 -1 (-3950 6600)(-4350 6600);
WIRE 16 -1 (-3950 6675)(-3950 6600);
WIRE 16 -1 (-3950 6400)(-3950 6600);
DOT 1 (-1200 4575);
DOT 1 (-5900 3100);
DOT 1 (-4075 3625);
DOT 1 (-5875 3100);
DOT 1 (-2625 3725);
DOT 1 (-7200 3200);
DOT 1 (-2025 4025);
DOT 1 (175 4325);
DOT 1 (-1150 5325);
DOT 1 (-825 5325);
DOT 1 (-825 5725);
DOT 1 (-425 5725);
DOT 1 (-251 5725);
DOT 1 (-2700 3725);
DOT 1 (675 4625);
DOT 1 (675 4725);
DOT 1 (1150 4900);
DOT 1 (675 5300);
DOT 1 (775 5300);
DOT 1 (-5050 5250);
DOT 1 (-3375 7175);
DOT 1 (-3950 6600);
DOT 1 (-5875 4925);
DOT 1 (-5775 4925);
DOT 1 (-5975 7325);
DOT 1 (-5650 7325);
DOT 1 (-5650 7725);
DOT 1 (-5325 7725);
DOT 1 (-5151 7725);
DOT 1 (-3475 7575);
DOT 1 (-3375 7575);
DOT 1 (-3475 6875);
DOT 1 (-4350 6600);
DOT 1 (-3050 7575);
DOT 1 (-3475 6975);
DOT 1 (-2350 7425);
DOT 1 (-2350 7000);
DOT 1 (-5125 5250);
DOT 1 (-1800 7000);
DOT 1 (-1275 7425);
DOT 1 (-1275 7000);
DOT 1 (-1800 7425);
FORCENOTE
20220519 ADD U330,U99 FOR P3V3
(-4225 2775) 0;
DISPLAY LEFT (-4225 2775);
DISPLAY 1.170213 (-4225 2775);
PAINT WHITE (-4225 2775);
FORCENOTE
20220317 ADD ADD R4638,R4639,R4640,R4641
(-2600 6050) 0;
DISPLAY LEFT (-2600 6050);
DISPLAY 1.170213 (-2600 6050);
PAINT WHITE (-2600 6050);
FORCENOTE
OD OUTPUT
(-3525 3325) 0;
DISPLAY LEFT (-3525 3325);
DISPLAY 0.808511 (-3525 3325);
PAINT PINK (-3525 3325);
FORCENOTE
PUSH PULL OUTPUT
(-6950 2925) 0;
DISPLAY LEFT (-6950 2925);
DISPLAY 0.808511 (-6950 2925);
PAINT PINK (-6950 2925);
FORCENOTE
20220225 ADD U324
(-2600 6125) 0;
DISPLAY LEFT (-2600 6125);
DISPLAY 1.170213 (-2600 6125);
PAINT WHITE (-2600 6125);
QUIT
